FILE_TYPE = MACRO_DRAWING;
SET COLOR_WIRE YELLOW;
SET COLOR_PROP ORANGE;
SET COLOR_DOT WHITE;
SET COLOR_ARC YELLOW;
SET COLOR_BODY GREEN;
SET COLOR_NOTE PURPLE;
SET PROP_DISPLAY VALUE;
SET PAGE_NUMBER P325;
FORCEADD UNIVERSAL_GND..1
(-1875 -2125);
FORCEPROP 3 LASTPIN (-1875 -2075) SIG_NAME AGND_HSC\g
J 0
(-1865 -2065);
DISPLAY 0.659574 (-1865 -2065);
PAINT MONO (-1865 -2065);
DISPLAY INVISIBLE (-1865 -2065);
FORCEPROP 1 LAST HDL_POWER AGND_HSC
J 1
(-1850 -2200);
DISPLAY 0.723404 (-1850 -2200);
PAINT GREEN (-1850 -2200);
FORCEPROP 2 LAST CDS_LIB logical_power
J 0
(-1875 -2125);
DISPLAY INVISIBLE (-1875 -2125);
FORCEPROP 1 LAST PATH I1
J 0
(-1800 -2125);
DISPLAY 0.872340 (-1800 -2125);
PAINT AQUA (-1800 -2125);
DISPLAY INVISIBLE (-1800 -2125);
FORCEADD OFFPAGE..4
R 2
(-1200 -1175);
FORCEPROP 2 LAST $XR2 303 
J 0
(-1692 -1175);
DISPLAY 0.638298 (-1692 -1175);
PAINT MONO (-1692 -1175);
FORCEPROP 2 LAST $XR1 302 
J 0
(-1572 -1175);
DISPLAY 0.638298 (-1572 -1175);
PAINT MONO (-1572 -1175);
FORCEPROP 2 LAST $XR0 301 
J 0
(-1452 -1175);
DISPLAY 0.638298 (-1452 -1175);
PAINT MONO (-1452 -1175);
FORCEPROP 1 LAST COMMENT_BODY TRUE
J 2
(-1175 -1275);
DISPLAY 0.872340 (-1175 -1275);
PAINT GREEN (-1175 -1275);
DISPLAY INVISIBLE (-1175 -1275);
FORCEPROP 1 LAST OFFPAGE TRUE
J 2
(-1525 -1300);
DISPLAY 0.872340 (-1525 -1300);
PAINT GREEN (-1525 -1300);
DISPLAY INVISIBLE (-1525 -1300);
FORCEPROP 2 LAST CDS_LIB standard
J 0
(-1200 -1175);
DISPLAY INVISIBLE (-1200 -1175);
FORCEPROP 2 LAST PATH I10
J 0
(-1450 -1125);
DISPLAY 1.021277 (-1450 -1125);
DISPLAY INVISIBLE (-1450 -1125);
FORCEADD Q_CAP..1
(-1150 -1825);
FORCEPROP 1 LAST PART_NUMBER CH21006KB16
J 0
(-1075 -1925);
DISPLAY 0.723404 (-1075 -1925);
PAINT WHITE (-1075 -1925);
DISPLAY INVISIBLE (-1075 -1925);
FORCEPROP 1 LAST VALUE 1NF
J 0
(-1075 -1775);
DISPLAY 0.723404 (-1075 -1775);
PAINT SKYBLUE (-1075 -1775);
FORCEPROP 1 LAST VOLTAGE 50V
J 0
(-1075 -1825);
DISPLAY 0.723404 (-1075 -1825);
PAINT SKYBLUE (-1075 -1825);
FORCEPROP 1 LAST MATERIAL EMPTY
J 0
(-1075 -1875);
DISPLAY 0.723404 (-1075 -1875);
PAINT RED (-1075 -1875);
FORCEPROP 1 LAST PACK_TYPE 0402
J 0
(-1075 -1975);
DISPLAY 0.723404 (-1075 -1975);
PAINT SKYBLUE (-1075 -1975);
FORCEPROP 1 LAST LOCATION PC2349
J 0
(-1075 -1725);
DISPLAY 0.808511 (-1075 -1725);
PAINT AQUA (-1075 -1725);
FORCEPROP 1 LASTPIN (-1150 -1725) $PN 1
J 0
(-1140 -1745);
DISPLAY 0.787234 (-1140 -1745);
PAINT MONO (-1140 -1745);
FORCEPROP 1 LASTPIN (-1150 -1925) $PN 2
J 0
(-1140 -1945);
DISPLAY 0.787234 (-1140 -1945);
PAINT MONO (-1140 -1945);
FORCEPROP 1 LAST TOLERANCE 10%
J 0
(-1100 -1875);
DISPLAY 0.978723 (-1100 -1875);
PAINT SKYBLUE (-1100 -1875);
DISPLAY INVISIBLE (-1100 -1875);
FORCEPROP 2 LAST CDS_LIB pure_quanta
J 0
(-1150 -1825);
DISPLAY INVISIBLE (-1150 -1825);
FORCEPROP 1 LAST PATH I11
J 0
(-1100 -1675);
DISPLAY 0.978723 (-1100 -1675);
PAINT WHITE (-1100 -1675);
DISPLAY INVISIBLE (-1100 -1675);
FORCEPROP 0 LAST $SEC 1
J 0
(-1075 -1675);
DISPLAY 0.680851 (-1075 -1675);
PAINT MONO (-1075 -1675);
DISPLAY INVISIBLE (-1075 -1675);
FORCEPROP 0 LAST CDS_SEC 1
J 0
(-1075 -1675);
DISPLAY 1.021277 (-1075 -1675);
DISPLAY INVISIBLE (-1075 -1675);
FORCEADD Q_RES..2
(-650 -1825);
FORCEPROP 1 LAST PART_NUMBER CS22002BB07
J 0
(-600 -1925);
DISPLAY 0.723404 (-600 -1925);
PAINT WHITE (-600 -1925);
DISPLAY INVISIBLE (-600 -1925);
FORCEPROP 1 LAST VALUE 2K
J 0
(-595 -1725);
DISPLAY 0.723404 (-595 -1725);
PAINT SKYBLUE (-595 -1725);
FORCEPROP 1 LAST TOLERANCE 0.1%
J 0
(-595 -1775);
DISPLAY 0.723404 (-595 -1775);
PAINT SKYBLUE (-595 -1775);
FORCEPROP 1 LAST WATTAGE 1/16W
J 0
(-600 -1825);
DISPLAY 0.723404 (-600 -1825);
PAINT SKYBLUE (-600 -1825);
FORCEPROP 1 LAST MATERIAL CHIP
J 0
(-600 -1875);
DISPLAY 0.723404 (-600 -1875);
PAINT SKYBLUE (-600 -1875);
FORCEPROP 1 LAST PACK_TYPE 0402LF
J 0
(-600 -1975);
DISPLAY 0.723404 (-600 -1975);
PAINT SKYBLUE (-600 -1975);
FORCEPROP 2 LAST ROOM HSC1_BOM1
J 0
(-625 -2075);
DISPLAY 1.021277 (-625 -2075);
FORCEPROP 1 LAST LOCATION PR3987
J 0
(-600 -1675);
DISPLAY 0.723404 (-600 -1675);
PAINT AQUA (-600 -1675);
FORCEPROP 1 LASTPIN (-650 -1725) $PN 1
J 0
(-645 -1763);
DISPLAY 0.787234 (-645 -1763);
PAINT MONO (-645 -1763);
FORCEPROP 1 LASTPIN (-650 -1925) $PN 2
J 0
(-645 -1915);
DISPLAY 0.787234 (-645 -1915);
PAINT MONO (-645 -1915);
FORCEPROP 2 LAST CDS_LIB pure_quanta
J 0
(-650 -1825);
DISPLAY INVISIBLE (-650 -1825);
FORCEPROP 1 LAST PATH I12
J 0
(-600 -1650);
DISPLAY 0.978723 (-600 -1650);
PAINT WHITE (-600 -1650);
DISPLAY INVISIBLE (-600 -1650);
FORCEPROP 0 LAST $SEC 1
J 0
(-575 -1625);
DISPLAY 0.680851 (-575 -1625);
PAINT MONO (-575 -1625);
DISPLAY INVISIBLE (-575 -1625);
FORCEPROP 0 LAST CDS_SEC 1
J 0
(-575 -1625);
DISPLAY 1.021277 (-575 -1625);
DISPLAY INVISIBLE (-575 -1625);
FORCEADD Q_RES..2
(-125 -1825);
FORCEPROP 1 LAST PART_NUMBER CS22002BB07
J 0
(-75 -1925);
DISPLAY 0.723404 (-75 -1925);
PAINT WHITE (-75 -1925);
DISPLAY INVISIBLE (-75 -1925);
FORCEPROP 1 LAST VALUE 2K
J 0
(-70 -1725);
DISPLAY 0.723404 (-70 -1725);
PAINT SKYBLUE (-70 -1725);
FORCEPROP 2 LAST ROOM HSC1_BOM1
J 0
(-75 -2075);
DISPLAY 1.021277 (-75 -2075);
FORCEPROP 1 LAST PACK_TYPE 0402LF
J 0
(-75 -1975);
DISPLAY 0.723404 (-75 -1975);
PAINT SKYBLUE (-75 -1975);
FORCEPROP 1 LAST MATERIAL CHIP
J 0
(-75 -1875);
DISPLAY 0.723404 (-75 -1875);
PAINT SKYBLUE (-75 -1875);
FORCEPROP 1 LAST WATTAGE 1/16W
J 0
(-75 -1825);
DISPLAY 0.723404 (-75 -1825);
PAINT SKYBLUE (-75 -1825);
FORCEPROP 1 LAST TOLERANCE 0.1%
J 0
(-70 -1775);
DISPLAY 0.723404 (-70 -1775);
PAINT SKYBLUE (-70 -1775);
FORCEPROP 1 LAST LOCATION PR3991
J 0
(-70 -1675);
DISPLAY 0.723404 (-70 -1675);
PAINT AQUA (-70 -1675);
FORCEPROP 1 LASTPIN (-125 -1725) $PN 1
J 0
(-120 -1763);
DISPLAY 0.787234 (-120 -1763);
PAINT MONO (-120 -1763);
FORCEPROP 1 LASTPIN (-125 -1925) $PN 2
J 0
(-120 -1915);
DISPLAY 0.787234 (-120 -1915);
PAINT MONO (-120 -1915);
FORCEPROP 2 LAST CDS_LIB pure_quanta
J 0
(-125 -1825);
DISPLAY INVISIBLE (-125 -1825);
FORCEPROP 1 LAST PATH I13
J 0
(-75 -1650);
DISPLAY 0.978723 (-75 -1650);
PAINT WHITE (-75 -1650);
DISPLAY INVISIBLE (-75 -1650);
FORCEPROP 0 LAST $SEC 1
J 0
(-50 -1625);
DISPLAY 0.680851 (-50 -1625);
PAINT MONO (-50 -1625);
DISPLAY INVISIBLE (-50 -1625);
FORCEPROP 0 LAST CDS_SEC 1
J 0
(-50 -1625);
DISPLAY 1.021277 (-50 -1625);
DISPLAY INVISIBLE (-50 -1625);
FORCEADD Q_RES..1
(-1075 -1000);
FORCEPROP 1 LAST PART_NUMBER CS41202FB05
J 0
(-950 -1000);
DISPLAY 0.723404 (-950 -1000);
PAINT WHITE (-950 -1000);
DISPLAY INVISIBLE (-950 -1000);
FORCEPROP 1 LAST VALUE 120K
J 2
(-1100 -1075);
DISPLAY 0.723404 (-1100 -1075);
PAINT SKYBLUE (-1100 -1075);
FORCEPROP 1 LAST MATERIAL CHIP
J 0
(-1025 -1125);
DISPLAY 0.723404 (-1025 -1125);
PAINT SKYBLUE (-1025 -1125);
FORCEPROP 1 LAST TOLERANCE 1%
J 0
(-1050 -1075);
DISPLAY 0.723404 (-1050 -1075);
PAINT SKYBLUE (-1050 -1075);
FORCEPROP 1 LAST PACK_TYPE 0402LF
J 0
(-950 -1075);
DISPLAY 0.723404 (-950 -1075);
PAINT SKYBLUE (-950 -1075);
FORCEPROP 2 LAST ROOM HSC1_BOM1
J 0
(-1275 -950);
DISPLAY 1.021277 (-1275 -950);
FORCEPROP 1 LAST WATTAGE 1/16W
J 2
(-1050 -1125);
DISPLAY 0.723404 (-1050 -1125);
PAINT SKYBLUE (-1050 -1125);
FORCEPROP 1 LAST LOCATION PR3984
J 0
(-1375 -1000);
DISPLAY 0.723404 (-1375 -1000);
PAINT AQUA (-1375 -1000);
FORCEPROP 1 LASTPIN (-1175 -1000) $PN 1
J 0
(-1163 -988);
DISPLAY 0.787234 (-1163 -988);
PAINT MONO (-1163 -988);
FORCEPROP 1 LASTPIN (-975 -1000) $PN 2
J 0
(-1013 -988);
DISPLAY 0.787234 (-1013 -988);
PAINT MONO (-1013 -988);
FORCEPROP 2 LAST CDS_LIB pure_quanta
J 0
(-1075 -1000);
DISPLAY INVISIBLE (-1075 -1000);
FORCEPROP 1 LAST PATH I14
J 0
(-1125 -850);
DISPLAY 0.978723 (-1125 -850);
PAINT WHITE (-1125 -850);
DISPLAY INVISIBLE (-1125 -850);
FORCEPROP 0 LAST $SEC 1
J 0
(-1025 -925);
DISPLAY 0.680851 (-1025 -925);
PAINT MONO (-1025 -925);
DISPLAY INVISIBLE (-1025 -925);
FORCEPROP 0 LAST CDS_SEC 1
J 0
(-1025 -925);
DISPLAY 1.021277 (-1025 -925);
DISPLAY INVISIBLE (-1025 -925);
FORCEADD OFFPAGE..5
(-225 -1600);
FORCEPROP 2 LAST $XR2 301 
J 0
(-480 -1636);
DISPLAY 0.638298 (-480 -1636);
PAINT MONO (-480 -1636);
FORCEPROP 2 LAST $XR1 303 
J 0
(-600 -1600);
DISPLAY 0.638298 (-600 -1600);
PAINT MONO (-600 -1600);
FORCEPROP 2 LAST $XR0 302 
J 0
(-480 -1600);
DISPLAY 0.638298 (-480 -1600);
PAINT MONO (-480 -1600);
FORCEPROP 1 LAST COMMENT_BODY TRUE
J 0
(-125 -1675);
DISPLAY 1.170213 (-125 -1675);
PAINT GREEN (-125 -1675);
DISPLAY INVISIBLE (-125 -1675);
FORCEPROP 1 LAST OFFPAGE TRUE
J 0
(100 -1725);
DISPLAY 0.872340 (100 -1725);
PAINT AQUA (100 -1725);
DISPLAY INVISIBLE (100 -1725);
FORCEPROP 2 LAST CDS_LIB standard
J 0
(-225 -1600);
DISPLAY INVISIBLE (-225 -1600);
FORCEPROP 2 LAST PATH I15
J 0
(-475 -1550);
DISPLAY 1.021277 (-475 -1550);
DISPLAY INVISIBLE (-475 -1550);
FORCEADD Q_RES..1
(-475 -1175);
FORCEPROP 1 LAST PART_NUMBER CS00002JB13
J 0
(-800 -1225);
DISPLAY 0.723404 (-800 -1225);
PAINT WHITE (-800 -1225);
DISPLAY INVISIBLE (-800 -1225);
FORCEPROP 1 LAST VALUE 0
J 2
(-300 -1150);
DISPLAY 0.723404 (-300 -1150);
PAINT SKYBLUE (-300 -1150);
FORCEPROP 1 LAST MATERIAL CHIP
J 0
(-325 -1275);
DISPLAY 0.723404 (-325 -1275);
PAINT SKYBLUE (-325 -1275);
FORCEPROP 1 LAST TOLERANCE 5%
J 0
(-350 -1225);
DISPLAY 0.723404 (-350 -1225);
PAINT SKYBLUE (-350 -1225);
FORCEPROP 1 LAST PACK_TYPE 0402LF
J 0
(-550 -1275);
DISPLAY 0.723404 (-550 -1275);
PAINT SKYBLUE (-550 -1275);
FORCEPROP 2 LAST ROOM HSC1_BOM1
J 0
(-650 -1125);
DISPLAY 1.021277 (-650 -1125);
FORCEPROP 1 LAST WATTAGE 1/16W
J 2
(-600 -1275);
DISPLAY 0.723404 (-600 -1275);
PAINT SKYBLUE (-600 -1275);
FORCEPROP 1 LAST LOCATION PR3989
J 0
(-775 -1175);
DISPLAY 0.723404 (-775 -1175);
PAINT AQUA (-775 -1175);
FORCEPROP 1 LASTPIN (-575 -1175) $PN 1
J 0
(-563 -1163);
DISPLAY 0.787234 (-563 -1163);
PAINT MONO (-563 -1163);
FORCEPROP 1 LASTPIN (-375 -1175) $PN 2
J 0
(-413 -1163);
DISPLAY 0.787234 (-413 -1163);
PAINT MONO (-413 -1163);
FORCEPROP 2 LAST CDS_LIB pure_quanta
J 0
(-475 -1175);
DISPLAY INVISIBLE (-475 -1175);
FORCEPROP 1 LAST PATH I16
J 0
(-525 -1025);
DISPLAY 0.978723 (-525 -1025);
PAINT WHITE (-525 -1025);
DISPLAY INVISIBLE (-525 -1025);
FORCEPROP 0 LAST $SEC 1
J 0
(-350 -1100);
DISPLAY 0.680851 (-350 -1100);
PAINT MONO (-350 -1100);
DISPLAY INVISIBLE (-350 -1100);
FORCEPROP 0 LAST CDS_SEC 1
J 0
(-350 -1100);
DISPLAY 1.021277 (-350 -1100);
DISPLAY INVISIBLE (-350 -1100);
FORCEADD MP5991GLUZ..1
(850 -1075);
FORCEPROP 1 LAST PART_NUMBER AL005991A00
J 0
(525 -225);
DISPLAY 0.723404 (525 -225);
PAINT GREEN (525 -225);
DISPLAY INVISIBLE (525 -225);
FORCEPROP 2 LAST PART_TYPE SMLF
J 0
(525 -125);
DISPLAY 1.021277 (525 -125);
FORCEPROP 1 LAST MATERIAL IC
J 0
(525 -275);
DISPLAY 0.723404 (525 -275);
PAINT GREEN (525 -275);
FORCEPROP 2 LAST VALUE MP5991GLU-Z
J 0
(525 -175);
DISPLAY 1.021277 (525 -175);
FORCEPROP 2 LAST ROOM HSC1_BOM1
J 0
(525 0);
DISPLAY 1.021277 (525 0);
FORCEPROP 1 LAST LOCATION PU297
J 0
(525 -75);
DISPLAY 1.148936 (525 -75);
PAINT GREEN (525 -75);
FORCEPROP 2 LASTPIN (375 -1500) $PN 23
J 2
(365 -1490);
DISPLAY 0.680851 (365 -1490);
PAINT MONO (365 -1490);
FORCEPROP 2 LASTPIN (1325 -1150) $PN 3
J 0
(1335 -1140);
DISPLAY 0.680851 (1335 -1140);
PAINT MONO (1335 -1140);
FORCEPROP 2 LASTPIN (1325 -1250) $PN 6
J 0
(1335 -1240);
DISPLAY 0.680851 (1335 -1240);
PAINT MONO (1335 -1240);
FORCEPROP 2 LASTPIN (375 -1800) $PN 20
J 2
(365 -1790);
DISPLAY 0.680851 (365 -1790);
PAINT MONO (365 -1790);
FORCEPROP 2 LASTPIN (1325 -1450) $PN 5
J 0
(1335 -1440);
DISPLAY 0.680851 (1335 -1440);
PAINT MONO (1335 -1440);
FORCEPROP 2 LASTPIN (375 -1600) $PN 22
J 2
(365 -1590);
DISPLAY 0.680851 (365 -1590);
PAINT MONO (365 -1590);
FORCEPROP 2 LASTPIN (375 -1000) $PN 8
J 2
(365 -990);
DISPLAY 0.680851 (365 -990);
PAINT MONO (365 -990);
FORCEPROP 2 LASTPIN (1325 -1350) $PN 7
J 0
(1335 -1340);
DISPLAY 0.680851 (1335 -1340);
PAINT MONO (1335 -1340);
FORCEPROP 2 LASTPIN (375 -1400) $PN 24
J 2
(365 -1390);
DISPLAY 0.680851 (365 -1390);
PAINT MONO (365 -1390);
FORCEPROP 2 LASTPIN (375 -1300) $PN 4
J 2
(365 -1290);
DISPLAY 0.680851 (365 -1290);
PAINT MONO (365 -1290);
FORCEPROP 2 LASTPIN (375 -1100) $PN 17
J 2
(365 -1090);
DISPLAY 0.680851 (365 -1090);
PAINT MONO (365 -1090);
FORCEPROP 2 LASTPIN (1325 -1650) $PN 19
J 0
(1335 -1640);
DISPLAY 0.680851 (1335 -1640);
PAINT MONO (1335 -1640);
FORCEPROP 2 LASTPIN (375 -900) $PN 21
J 2
(365 -890);
DISPLAY 0.680851 (365 -890);
PAINT MONO (365 -890);
FORCEPROP 2 LASTPIN (375 -350) $PN 9
J 2
(365 -340);
DISPLAY 0.680851 (365 -340);
PAINT MONO (365 -340);
FORCEPROP 2 LASTPIN (375 -400) $PN 10
J 2
(365 -390);
DISPLAY 0.680851 (365 -390);
PAINT MONO (365 -390);
FORCEPROP 2 LASTPIN (375 -450) $PN 11
J 2
(365 -440);
DISPLAY 0.680851 (365 -440);
PAINT MONO (365 -440);
FORCEPROP 2 LASTPIN (375 -500) $PN 12
J 2
(365 -490);
DISPLAY 0.680851 (365 -490);
PAINT MONO (365 -490);
FORCEPROP 2 LASTPIN (375 -550) $PN 13
J 2
(365 -540);
DISPLAY 0.680851 (365 -540);
PAINT MONO (365 -540);
FORCEPROP 2 LASTPIN (375 -600) $PN 14
J 2
(365 -590);
DISPLAY 0.680851 (365 -590);
PAINT MONO (365 -590);
FORCEPROP 2 LASTPIN (375 -650) $PN 15
J 2
(365 -640);
DISPLAY 0.680851 (365 -640);
PAINT MONO (365 -640);
FORCEPROP 2 LASTPIN (375 -700) $PN 16
J 2
(365 -690);
DISPLAY 0.680851 (365 -690);
PAINT MONO (365 -690);
FORCEPROP 2 LASTPIN (375 -750) $PN 33
J 2
(365 -740);
DISPLAY 0.680851 (365 -740);
PAINT MONO (365 -740);
FORCEPROP 2 LASTPIN (1325 -350) $PN 1
J 0
(1335 -340);
DISPLAY 0.680851 (1335 -340);
PAINT MONO (1335 -340);
FORCEPROP 2 LASTPIN (1325 -400) $PN 2
J 0
(1335 -390);
DISPLAY 0.680851 (1335 -390);
PAINT MONO (1335 -390);
FORCEPROP 2 LASTPIN (1325 -450) $PN 25
J 0
(1335 -440);
DISPLAY 0.680851 (1335 -440);
PAINT MONO (1335 -440);
FORCEPROP 2 LASTPIN (1325 -500) $PN 26
J 0
(1335 -490);
DISPLAY 0.680851 (1335 -490);
PAINT MONO (1335 -490);
FORCEPROP 2 LASTPIN (1325 -550) $PN 27
J 0
(1335 -540);
DISPLAY 0.680851 (1335 -540);
PAINT MONO (1335 -540);
FORCEPROP 2 LASTPIN (1325 -600) $PN 28
J 0
(1335 -590);
DISPLAY 0.680851 (1335 -590);
PAINT MONO (1335 -590);
FORCEPROP 2 LASTPIN (1325 -650) $PN 29
J 0
(1335 -640);
DISPLAY 0.680851 (1335 -640);
PAINT MONO (1335 -640);
FORCEPROP 2 LASTPIN (1325 -700) $PN 30
J 0
(1335 -690);
DISPLAY 0.680851 (1335 -690);
PAINT MONO (1335 -690);
FORCEPROP 2 LASTPIN (1325 -750) $PN 31
J 0
(1335 -740);
DISPLAY 0.680851 (1335 -740);
PAINT MONO (1335 -740);
FORCEPROP 2 LASTPIN (1325 -800) $PN 32
J 0
(1335 -790);
DISPLAY 0.680851 (1335 -790);
PAINT MONO (1335 -790);
FORCEPROP 2 LASTPIN (1325 -1550) $PN 18
J 0
(1335 -1540);
DISPLAY 0.680851 (1335 -1540);
PAINT MONO (1335 -1540);
FORCEPROP 1 LAST NEEDS_NO_SIZE TRUE
J 0
(850 -1075);
DISPLAY 0.723404 (850 -1075);
PAINT GREEN (850 -1075);
DISPLAY INVISIBLE (850 -1075);
FORCEPROP 1 LAST CDS_LMAN_SYM_OUTLINE -325,775,325,-775
J 0
(850 -1075);
DISPLAY 0.468085 (850 -1075);
PAINT GREEN (850 -1075);
DISPLAY INVISIBLE (850 -1075);
FORCEPROP 2 LAST CDS_LIB pure_quanta
J 0
(850 -1075);
DISPLAY INVISIBLE (850 -1075);
FORCEPROP 2 LAST SEC_TYPE 
J 0
(550 150);
DISPLAY 1.021277 (550 150);
DISPLAY INVISIBLE (550 150);
FORCEPROP 1 LAST PATH I17
J 0
(850 -1075);
DISPLAY 0.723404 (850 -1075);
PAINT GREEN (850 -1075);
DISPLAY INVISIBLE (850 -1075);
FORCEPROP 2 LAST SEC 1
J 0
(550 150);
DISPLAY 0.680851 (550 150);
PAINT MONO (550 150);
DISPLAY INVISIBLE (550 150);
FORCEADD UNIVERSAL_POWER..1
(-125 -200);
FORCEPROP 3 LASTPIN (-125 -250) SIG_NAME P12V_PSU\g
J 0
(-115 -240);
DISPLAY 0.659574 (-115 -240);
PAINT MONO (-115 -240);
DISPLAY INVISIBLE (-115 -240);
FORCEPROP 1 LAST HDL_POWER P12V_PSU
J 1
(-125 -150);
DISPLAY 0.723404 (-125 -150);
PAINT GREEN (-125 -150);
FORCEPROP 2 LAST ROOM AUX_SW
J 0
(-125 -100);
DISPLAY 0.617021 (-125 -100);
DISPLAY INVISIBLE (-125 -100);
FORCEPROP 2 LAST CDS_LIB logical_power
J 0
(-125 -200);
DISPLAY INVISIBLE (-125 -200);
FORCEPROP 2 LAST BOM_COST MIO_VRD_SB
J 0
(-125 -100);
DISPLAY 0.617021 (-125 -100);
PAINT PURPLE (-125 -100);
DISPLAY INVISIBLE (-125 -100);
FORCEPROP 1 LAST PATH I18
J 0
(-75 -175);
DISPLAY 0.872340 (-75 -175);
PAINT AQUA (-75 -175);
DISPLAY INVISIBLE (-75 -175);
FORCEADD Q_CAP..1
(-2775 1600);
FORCEPROP 1 LAST PART_NUMBER CH5104KEB02
J 0
(-2700 1550);
DISPLAY 0.723404 (-2700 1550);
PAINT WHITE (-2700 1550);
DISPLAY INVISIBLE (-2700 1550);
FORCEPROP 1 LAST VALUE 1UF
J 0
(-2700 1700);
DISPLAY 0.723404 (-2700 1700);
PAINT SKYBLUE (-2700 1700);
FORCEPROP 1 LAST MATERIAL X6S
J 0
(-2700 1600);
DISPLAY 0.723404 (-2700 1600);
PAINT SKYBLUE (-2700 1600);
FORCEPROP 1 LAST PACK_TYPE C0402
J 0
(-2700 1500);
DISPLAY 0.723404 (-2700 1500);
PAINT SKYBLUE (-2700 1500);
FORCEPROP 1 LAST VOLTAGE 25V
J 0
(-2700 1650);
DISPLAY 0.723404 (-2700 1650);
PAINT SKYBLUE (-2700 1650);
FORCEPROP 2 LAST ROOM HSC1_BOM1
J 0
(-2700 1800);
DISPLAY 1.021277 (-2700 1800);
FORCEPROP 1 LAST LOCATION PC3272
J 0
(-2700 1750);
DISPLAY 0.723404 (-2700 1750);
PAINT AQUA (-2700 1750);
FORCEPROP 1 LASTPIN (-2775 1700) $PN 1
J 0
(-2765 1680);
DISPLAY 0.787234 (-2765 1680);
PAINT MONO (-2765 1680);
FORCEPROP 1 LASTPIN (-2775 1500) $PN 2
J 0
(-2765 1480);
DISPLAY 0.787234 (-2765 1480);
PAINT MONO (-2765 1480);
FORCEPROP 1 LAST TOLERANCE 10%
J 0
(-2725 1550);
DISPLAY 0.978723 (-2725 1550);
PAINT SKYBLUE (-2725 1550);
DISPLAY INVISIBLE (-2725 1550);
FORCEPROP 2 LAST CDS_LIB pure_quanta
J 0
(-2775 1600);
DISPLAY INVISIBLE (-2775 1600);
FORCEPROP 1 LAST PATH I19
J 0
(-2725 1750);
DISPLAY 0.978723 (-2725 1750);
PAINT WHITE (-2725 1750);
DISPLAY INVISIBLE (-2725 1750);
FORCEPROP 0 LAST $SEC 1
J 0
(-2700 1800);
DISPLAY 0.680851 (-2700 1800);
PAINT MONO (-2700 1800);
DISPLAY INVISIBLE (-2700 1800);
FORCEPROP 0 LAST CDS_SEC 1
J 0
(-2700 1800);
DISPLAY 1.021277 (-2700 1800);
DISPLAY INVISIBLE (-2700 1800);
FORCEADD Q_CAP..1
(-1875 -1825);
FORCEPROP 1 LAST PART_NUMBER TMP_QCH12206KB14
J 0
(-1800 -1925);
DISPLAY 0.723404 (-1800 -1925);
PAINT WHITE (-1800 -1925);
DISPLAY INVISIBLE (-1800 -1925);
FORCEPROP 1 LAST VOLTAGE 50V
J 0
(-1800 -1825);
DISPLAY 0.723404 (-1800 -1825);
PAINT SKYBLUE (-1800 -1825);
FORCEPROP 1 LAST PACK_TYPE 0402
J 0
(-1800 -1975);
DISPLAY 0.723404 (-1800 -1975);
PAINT SKYBLUE (-1800 -1975);
FORCEPROP 1 LAST VALUE 220PF
J 0
(-1800 -1775);
DISPLAY 0.723404 (-1800 -1775);
PAINT SKYBLUE (-1800 -1775);
FORCEPROP 1 LAST MATERIAL EMPTY
J 0
(-1800 -1875);
DISPLAY 0.723404 (-1800 -1875);
PAINT RED (-1800 -1875);
FORCEPROP 1 LAST LOCATION PC2225
J 0
(-1800 -1725);
DISPLAY 0.723404 (-1800 -1725);
PAINT AQUA (-1800 -1725);
FORCEPROP 1 LASTPIN (-1875 -1725) $PN 1
J 0
(-1865 -1745);
DISPLAY 0.787234 (-1865 -1745);
PAINT MONO (-1865 -1745);
FORCEPROP 1 LASTPIN (-1875 -1925) $PN 2
J 0
(-1865 -1945);
DISPLAY 0.787234 (-1865 -1945);
PAINT MONO (-1865 -1945);
FORCEPROP 2 LAST CDS_LIB pure_quanta
J 0
(-1875 -1825);
DISPLAY INVISIBLE (-1875 -1825);
FORCEPROP 1 LAST TOLERANCE 10%
J 0
(-1825 -1875);
DISPLAY 0.978723 (-1825 -1875);
PAINT SKYBLUE (-1825 -1875);
DISPLAY INVISIBLE (-1825 -1875);
FORCEPROP 1 LAST PATH I2
J 0
(-1825 -1675);
DISPLAY 0.978723 (-1825 -1675);
PAINT WHITE (-1825 -1675);
DISPLAY INVISIBLE (-1825 -1675);
FORCEPROP 0 LAST $SEC 1
J 0
(-1800 -1675);
DISPLAY 0.680851 (-1800 -1675);
PAINT MONO (-1800 -1675);
DISPLAY INVISIBLE (-1800 -1675);
FORCEPROP 0 LAST CDS_SEC 1
J 0
(-1800 -1675);
DISPLAY 1.021277 (-1800 -1675);
DISPLAY INVISIBLE (-1800 -1675);
FORCEADD UNIVERSAL_GND..1
(-2775 1300);
FORCEPROP 3 LASTPIN (-2775 1350) SIG_NAME AGND_HSC\g
J 0
(-2765 1360);
DISPLAY 0.659574 (-2765 1360);
PAINT MONO (-2765 1360);
DISPLAY INVISIBLE (-2765 1360);
FORCEPROP 1 LAST HDL_POWER AGND_HSC
J 1
(-2750 1225);
DISPLAY 0.723404 (-2750 1225);
PAINT GREEN (-2750 1225);
FORCEPROP 2 LAST CDS_LIB logical_power
J 0
(-2775 1300);
DISPLAY INVISIBLE (-2775 1300);
FORCEPROP 1 LAST PATH I20
J 0
(-2700 1300);
DISPLAY 0.872340 (-2700 1300);
PAINT AQUA (-2700 1300);
DISPLAY INVISIBLE (-2700 1300);
FORCEADD Q_RES..1
R 1
(-2775 2075);
FORCEPROP 1 LAST PART_NUMBER CS00002JB13
J 0
(-2700 1975);
DISPLAY 0.723404 (-2700 1975);
PAINT WHITE (-2700 1975);
DISPLAY INVISIBLE (-2700 1975);
FORCEPROP 1 LAST VALUE 0
R 2
J 0
(-2675 2200);
DISPLAY 0.723404 (-2675 2200);
PAINT SKYBLUE (-2675 2200);
FORCEPROP 1 LAST TOLERANCE 5%
J 0
(-2700 2125);
DISPLAY 0.723404 (-2700 2125);
PAINT SKYBLUE (-2700 2125);
FORCEPROP 1 LAST MATERIAL CHIP
J 0
(-2700 2075);
DISPLAY 0.787234 (-2700 2075);
PAINT SKYBLUE (-2700 2075);
FORCEPROP 1 LAST WATTAGE 1/16W
J 0
(-2700 2025);
DISPLAY 0.723404 (-2700 2025);
PAINT SKYBLUE (-2700 2025);
FORCEPROP 1 LAST PACK_TYPE 0402LF
J 0
(-2700 1925);
DISPLAY 0.723404 (-2700 1925);
PAINT SKYBLUE (-2700 1925);
FORCEPROP 2 LAST ROOM HSC1_BOM1
J 0
(-2700 2275);
DISPLAY 1.021277 (-2700 2275);
FORCEPROP 1 LAST LOCATION PR3980
J 0
(-2700 2225);
DISPLAY 0.723404 (-2700 2225);
PAINT AQUA (-2700 2225);
FORCEPROP 1 LASTPIN (-2775 1975) $PN 1
R 1
J 0
(-2787 1987);
DISPLAY 0.787234 (-2787 1987);
PAINT MONO (-2787 1987);
FORCEPROP 1 LASTPIN (-2775 2175) $PN 2
R 1
J 0
(-2787 2137);
DISPLAY 0.787234 (-2787 2137);
PAINT MONO (-2787 2137);
FORCEPROP 2 LAST CDS_LIB pure_quanta
J 0
(-2775 2075);
DISPLAY INVISIBLE (-2775 2075);
FORCEPROP 1 LAST PATH I21
R 1
J 0
(-2925 2025);
DISPLAY 0.978723 (-2925 2025);
PAINT WHITE (-2925 2025);
DISPLAY INVISIBLE (-2925 2025);
FORCEPROP 0 LAST $SEC 1
R 1
J 0
(-2700 2275);
DISPLAY 0.680851 (-2700 2275);
PAINT MONO (-2700 2275);
DISPLAY INVISIBLE (-2700 2275);
FORCEPROP 0 LAST CDS_SEC 1
R 1
J 0
(-2700 2275);
DISPLAY 1.021277 (-2700 2275);
DISPLAY INVISIBLE (-2700 2275);
FORCEADD UNIVERSAL_GND..1
(-1875 650);
FORCEPROP 3 LASTPIN (-1875 700) SIG_NAME AGND_HSC\g
J 0
(-1865 710);
DISPLAY 0.659574 (-1865 710);
PAINT MONO (-1865 710);
DISPLAY INVISIBLE (-1865 710);
FORCEPROP 1 LAST HDL_POWER AGND_HSC
J 1
(-1850 575);
DISPLAY 0.723404 (-1850 575);
PAINT GREEN (-1850 575);
FORCEPROP 2 LAST CDS_LIB logical_power
J 0
(-1875 650);
DISPLAY INVISIBLE (-1875 650);
FORCEPROP 1 LAST PATH I22
J 0
(-1800 650);
DISPLAY 0.872340 (-1800 650);
PAINT AQUA (-1800 650);
DISPLAY INVISIBLE (-1800 650);
FORCEADD Q_CAP..1
(-1875 950);
FORCEPROP 1 LAST PART_NUMBER TMP_QCH12206KB14
J 0
(-1800 850);
DISPLAY 0.723404 (-1800 850);
PAINT WHITE (-1800 850);
DISPLAY INVISIBLE (-1800 850);
FORCEPROP 1 LAST PACK_TYPE 0402
J 0
(-1800 800);
DISPLAY 0.723404 (-1800 800);
PAINT SKYBLUE (-1800 800);
FORCEPROP 1 LAST VOLTAGE 50V
J 0
(-1800 950);
DISPLAY 0.723404 (-1800 950);
PAINT SKYBLUE (-1800 950);
FORCEPROP 1 LAST MATERIAL EMPTY
J 0
(-1800 900);
DISPLAY 0.723404 (-1800 900);
PAINT RED (-1800 900);
FORCEPROP 1 LAST VALUE 220PF
J 0
(-1800 1000);
DISPLAY 0.723404 (-1800 1000);
PAINT SKYBLUE (-1800 1000);
FORCEPROP 1 LAST LOCATION PC2224
J 0
(-1800 1050);
DISPLAY 0.723404 (-1800 1050);
PAINT AQUA (-1800 1050);
FORCEPROP 1 LASTPIN (-1875 1050) $PN 1
J 0
(-1865 1030);
DISPLAY 0.787234 (-1865 1030);
PAINT MONO (-1865 1030);
FORCEPROP 1 LASTPIN (-1875 850) $PN 2
J 0
(-1865 830);
DISPLAY 0.787234 (-1865 830);
PAINT MONO (-1865 830);
FORCEPROP 2 LAST CDS_LIB pure_quanta
J 0
(-1875 950);
DISPLAY INVISIBLE (-1875 950);
FORCEPROP 1 LAST TOLERANCE 10%
J 0
(-1825 900);
DISPLAY 0.978723 (-1825 900);
PAINT SKYBLUE (-1825 900);
DISPLAY INVISIBLE (-1825 900);
FORCEPROP 1 LAST PATH I23
J 0
(-1825 1100);
DISPLAY 0.978723 (-1825 1100);
PAINT WHITE (-1825 1100);
DISPLAY INVISIBLE (-1825 1100);
FORCEPROP 0 LAST $SEC 1
J 0
(-1800 1100);
DISPLAY 0.680851 (-1800 1100);
PAINT MONO (-1800 1100);
DISPLAY INVISIBLE (-1800 1100);
FORCEPROP 0 LAST CDS_SEC 1
J 0
(-1800 1100);
DISPLAY 1.021277 (-1800 1100);
DISPLAY INVISIBLE (-1800 1100);
FORCEADD OFFPAGE..4
R 2
(-2050 1475);
FORCEPROP 2 LAST $XR2 303 
J 0
(-2332 1439);
DISPLAY 0.638298 (-2332 1439);
PAINT MONO (-2332 1439);
FORCEPROP 2 LAST $XR1 302 
J 0
(-2452 1475);
DISPLAY 0.638298 (-2452 1475);
PAINT MONO (-2452 1475);
FORCEPROP 2 LAST $XR0 301 
J 0
(-2332 1475);
DISPLAY 0.638298 (-2332 1475);
PAINT MONO (-2332 1475);
FORCEPROP 1 LAST COMMENT_BODY TRUE
J 2
(-2025 1375);
DISPLAY 0.872340 (-2025 1375);
PAINT GREEN (-2025 1375);
DISPLAY INVISIBLE (-2025 1375);
FORCEPROP 1 LAST OFFPAGE TRUE
J 2
(-2375 1350);
DISPLAY 0.872340 (-2375 1350);
PAINT GREEN (-2375 1350);
DISPLAY INVISIBLE (-2375 1350);
FORCEPROP 2 LAST CDS_LIB standard
J 0
(-2050 1475);
DISPLAY INVISIBLE (-2050 1475);
FORCEPROP 2 LAST PATH I24
J 0
(-2325 1525);
DISPLAY 1.021277 (-2325 1525);
DISPLAY INVISIBLE (-2325 1525);
FORCEADD UNIVERSAL_GND..1
(-1900 1700);
FORCEPROP 3 LASTPIN (-1900 1750) SIG_NAME AGND_HSC\g
J 0
(-1890 1760);
DISPLAY 0.659574 (-1890 1760);
PAINT MONO (-1890 1760);
DISPLAY INVISIBLE (-1890 1760);
FORCEPROP 1 LAST HDL_POWER AGND_HSC
J 1
(-1875 1625);
DISPLAY 0.723404 (-1875 1625);
PAINT GREEN (-1875 1625);
FORCEPROP 2 LAST CDS_LIB logical_power
J 0
(-1900 1700);
DISPLAY INVISIBLE (-1900 1700);
FORCEPROP 1 LAST PATH I25
J 0
(-1825 1700);
DISPLAY 0.872340 (-1825 1700);
PAINT AQUA (-1825 1700);
DISPLAY INVISIBLE (-1825 1700);
FORCEADD OFFPAGE..4
R 2
(-1225 1375);
FORCEPROP 2 LAST $XR2 303 
J 0
(-1717 1375);
DISPLAY 0.638298 (-1717 1375);
PAINT MONO (-1717 1375);
FORCEPROP 2 LAST $XR1 302 
J 0
(-1597 1375);
DISPLAY 0.638298 (-1597 1375);
PAINT MONO (-1597 1375);
FORCEPROP 2 LAST $XR0 301 
J 0
(-1477 1375);
DISPLAY 0.638298 (-1477 1375);
PAINT MONO (-1477 1375);
FORCEPROP 1 LAST COMMENT_BODY TRUE
J 2
(-1200 1275);
DISPLAY 0.872340 (-1200 1275);
PAINT GREEN (-1200 1275);
DISPLAY INVISIBLE (-1200 1275);
FORCEPROP 1 LAST OFFPAGE TRUE
J 2
(-1550 1250);
DISPLAY 0.872340 (-1550 1250);
PAINT GREEN (-1550 1250);
DISPLAY INVISIBLE (-1550 1250);
FORCEPROP 2 LAST CDS_LIB standard
J 0
(-1225 1375);
DISPLAY INVISIBLE (-1225 1375);
FORCEPROP 2 LAST PATH I26
J 0
(-1475 1425);
DISPLAY 1.021277 (-1475 1425);
DISPLAY INVISIBLE (-1475 1425);
FORCEADD OFFPAGE..4
R 2
(-1200 1600);
FORCEPROP 2 LAST $XR2 303 
J 0
(-1692 1600);
DISPLAY 0.638298 (-1692 1600);
PAINT MONO (-1692 1600);
FORCEPROP 2 LAST $XR1 302 
J 0
(-1572 1600);
DISPLAY 0.638298 (-1572 1600);
PAINT MONO (-1572 1600);
FORCEPROP 2 LAST $XR0 301 
J 0
(-1452 1600);
DISPLAY 0.638298 (-1452 1600);
PAINT MONO (-1452 1600);
FORCEPROP 1 LAST COMMENT_BODY TRUE
J 2
(-1175 1500);
DISPLAY 0.872340 (-1175 1500);
PAINT GREEN (-1175 1500);
DISPLAY INVISIBLE (-1175 1500);
FORCEPROP 1 LAST OFFPAGE TRUE
J 2
(-1525 1475);
DISPLAY 0.872340 (-1525 1475);
PAINT GREEN (-1525 1475);
DISPLAY INVISIBLE (-1525 1475);
FORCEPROP 2 LAST CDS_LIB standard
J 0
(-1200 1600);
DISPLAY INVISIBLE (-1200 1600);
FORCEPROP 2 LAST PATH I27
J 0
(-1450 1650);
DISPLAY 1.021277 (-1450 1650);
DISPLAY INVISIBLE (-1450 1650);
FORCEADD UNIVERSAL_POWER..1
(-2775 2325);
FORCEPROP 3 LASTPIN (-2775 2275) SIG_NAME HSC_VDD\g
J 0
(-2765 2285);
DISPLAY 0.659574 (-2765 2285);
PAINT MONO (-2765 2285);
DISPLAY INVISIBLE (-2765 2285);
FORCEPROP 1 LAST HDL_POWER HSC_VDD
J 1
(-2775 2375);
DISPLAY 0.723404 (-2775 2375);
PAINT GREEN (-2775 2375);
FORCEPROP 2 LAST ROOM AUX_SW
J 0
(-2775 2425);
DISPLAY 0.617021 (-2775 2425);
DISPLAY INVISIBLE (-2775 2425);
FORCEPROP 2 LAST BOM_COST MIO_VRD_SB
J 0
(-2775 2425);
DISPLAY 0.617021 (-2775 2425);
PAINT PURPLE (-2775 2425);
DISPLAY INVISIBLE (-2775 2425);
FORCEPROP 2 LAST CDS_LIB logical_power
J 0
(-2775 2325);
DISPLAY INVISIBLE (-2775 2325);
FORCEPROP 1 LAST PATH I28
J 0
(-2725 2350);
DISPLAY 0.872340 (-2725 2350);
PAINT AQUA (-2725 2350);
DISPLAY INVISIBLE (-2725 2350);
FORCEADD Q_CAP..1
(-1125 950);
FORCEPROP 1 LAST PART_NUMBER CH21006KB16
J 0
(-1050 850);
DISPLAY 0.723404 (-1050 850);
PAINT WHITE (-1050 850);
DISPLAY INVISIBLE (-1050 850);
FORCEPROP 1 LAST VOLTAGE 50V
J 0
(-1050 950);
DISPLAY 0.723404 (-1050 950);
PAINT SKYBLUE (-1050 950);
FORCEPROP 1 LAST PACK_TYPE 0402
J 0
(-1050 800);
DISPLAY 0.723404 (-1050 800);
PAINT SKYBLUE (-1050 800);
FORCEPROP 1 LAST MATERIAL EMPTY
J 0
(-1050 900);
DISPLAY 0.723404 (-1050 900);
PAINT RED (-1050 900);
FORCEPROP 1 LAST VALUE 1NF
J 0
(-1050 1000);
DISPLAY 0.723404 (-1050 1000);
PAINT SKYBLUE (-1050 1000);
FORCEPROP 1 LAST LOCATION PC2350
J 0
(-1050 1050);
DISPLAY 0.808511 (-1050 1050);
PAINT AQUA (-1050 1050);
FORCEPROP 1 LASTPIN (-1125 1050) $PN 1
J 0
(-1115 1030);
DISPLAY 0.787234 (-1115 1030);
PAINT MONO (-1115 1030);
FORCEPROP 1 LASTPIN (-1125 850) $PN 2
J 0
(-1115 830);
DISPLAY 0.787234 (-1115 830);
PAINT MONO (-1115 830);
FORCEPROP 1 LAST TOLERANCE 10%
J 0
(-1075 900);
DISPLAY 0.978723 (-1075 900);
PAINT SKYBLUE (-1075 900);
DISPLAY INVISIBLE (-1075 900);
FORCEPROP 2 LAST CDS_LIB pure_quanta
J 0
(-1125 950);
DISPLAY INVISIBLE (-1125 950);
FORCEPROP 1 LAST PATH I29
J 0
(-1075 1100);
DISPLAY 0.978723 (-1075 1100);
PAINT WHITE (-1075 1100);
DISPLAY INVISIBLE (-1075 1100);
FORCEPROP 0 LAST $SEC 1
J 0
(-1050 1100);
DISPLAY 0.680851 (-1050 1100);
PAINT MONO (-1050 1100);
DISPLAY INVISIBLE (-1050 1100);
FORCEPROP 0 LAST CDS_SEC 1
J 0
(-1050 1100);
DISPLAY 1.021277 (-1050 1100);
DISPLAY INVISIBLE (-1050 1100);
FORCEADD UNIVERSAL_GND..1
(-2750 -1475);
FORCEPROP 3 LASTPIN (-2750 -1425) SIG_NAME AGND_HSC\g
J 0
(-2740 -1415);
DISPLAY 0.659574 (-2740 -1415);
PAINT MONO (-2740 -1415);
DISPLAY INVISIBLE (-2740 -1415);
FORCEPROP 1 LAST HDL_POWER AGND_HSC
J 1
(-2725 -1550);
DISPLAY 0.723404 (-2725 -1550);
PAINT GREEN (-2725 -1550);
FORCEPROP 2 LAST CDS_LIB logical_power
J 0
(-2750 -1475);
DISPLAY INVISIBLE (-2750 -1475);
FORCEPROP 1 LAST PATH I3
J 0
(-2675 -1475);
DISPLAY 0.872340 (-2675 -1475);
PAINT AQUA (-2675 -1475);
DISPLAY INVISIBLE (-2675 -1475);
FORCEADD Q_RES..2
(-650 950);
FORCEPROP 1 LAST PART_NUMBER CS22002BB07
J 0
(-600 850);
DISPLAY 0.723404 (-600 850);
PAINT WHITE (-600 850);
DISPLAY INVISIBLE (-600 850);
FORCEPROP 1 LAST MATERIAL CHIP
J 0
(-600 900);
DISPLAY 0.723404 (-600 900);
PAINT SKYBLUE (-600 900);
FORCEPROP 1 LAST PACK_TYPE 0402LF
J 0
(-600 800);
DISPLAY 0.723404 (-600 800);
PAINT SKYBLUE (-600 800);
FORCEPROP 1 LAST VALUE 2K
J 0
(-595 1050);
DISPLAY 0.723404 (-595 1050);
PAINT SKYBLUE (-595 1050);
FORCEPROP 1 LAST TOLERANCE 0.1%
J 0
(-595 1000);
DISPLAY 0.723404 (-595 1000);
PAINT SKYBLUE (-595 1000);
FORCEPROP 1 LAST WATTAGE 1/16W
J 0
(-600 950);
DISPLAY 0.723404 (-600 950);
PAINT SKYBLUE (-600 950);
FORCEPROP 2 LAST ROOM HSC1_BOM1
J 0
(-575 1150);
DISPLAY 1.021277 (-575 1150);
FORCEPROP 1 LAST LOCATION PR3986
J 0
(-595 1100);
DISPLAY 0.723404 (-595 1100);
PAINT AQUA (-595 1100);
FORCEPROP 1 LASTPIN (-650 1050) $PN 1
J 0
(-645 1012);
DISPLAY 0.787234 (-645 1012);
PAINT MONO (-645 1012);
FORCEPROP 1 LASTPIN (-650 850) $PN 2
J 0
(-645 860);
DISPLAY 0.787234 (-645 860);
PAINT MONO (-645 860);
FORCEPROP 2 LAST CDS_LIB pure_quanta
J 0
(-650 950);
DISPLAY INVISIBLE (-650 950);
FORCEPROP 1 LAST PATH I30
J 0
(-600 1125);
DISPLAY 0.978723 (-600 1125);
PAINT WHITE (-600 1125);
DISPLAY INVISIBLE (-600 1125);
FORCEPROP 0 LAST $SEC 1
J 0
(-575 1150);
DISPLAY 0.680851 (-575 1150);
PAINT MONO (-575 1150);
DISPLAY INVISIBLE (-575 1150);
FORCEPROP 0 LAST CDS_SEC 1
J 0
(-575 1150);
DISPLAY 1.021277 (-575 1150);
DISPLAY INVISIBLE (-575 1150);
FORCEADD OFFPAGE..5
(-225 1175);
FORCEPROP 2 LAST $XR2 301 
J 0
(-990 1175);
DISPLAY 0.638298 (-990 1175);
PAINT MONO (-990 1175);
FORCEPROP 2 LAST $XR1 303 
J 0
(-870 1175);
DISPLAY 0.638298 (-870 1175);
PAINT MONO (-870 1175);
FORCEPROP 2 LAST $XR0 302 
J 0
(-750 1175);
DISPLAY 0.638298 (-750 1175);
PAINT MONO (-750 1175);
FORCEPROP 1 LAST COMMENT_BODY TRUE
J 0
(-125 1100);
DISPLAY 1.170213 (-125 1100);
PAINT GREEN (-125 1100);
DISPLAY INVISIBLE (-125 1100);
FORCEPROP 1 LAST OFFPAGE TRUE
J 0
(100 1050);
DISPLAY 0.872340 (100 1050);
PAINT AQUA (100 1050);
DISPLAY INVISIBLE (100 1050);
FORCEPROP 2 LAST CDS_LIB standard
J 0
(-225 1175);
DISPLAY INVISIBLE (-225 1175);
FORCEPROP 2 LAST PATH I31
J 0
(-475 1225);
DISPLAY 1.021277 (-475 1225);
DISPLAY INVISIBLE (-475 1225);
FORCEADD Q_RES..1
(-1075 1775);
FORCEPROP 1 LAST PART_NUMBER CS41202FB05
J 0
(-925 1775);
DISPLAY 0.723404 (-925 1775);
PAINT WHITE (-925 1775);
DISPLAY INVISIBLE (-925 1775);
FORCEPROP 1 LAST WATTAGE 1/16W
J 2
(-1050 1650);
DISPLAY 0.723404 (-1050 1650);
PAINT SKYBLUE (-1050 1650);
FORCEPROP 1 LAST MATERIAL CHIP
J 0
(-1025 1650);
DISPLAY 0.723404 (-1025 1650);
PAINT SKYBLUE (-1025 1650);
FORCEPROP 1 LAST TOLERANCE 1%
J 0
(-1050 1700);
DISPLAY 0.723404 (-1050 1700);
PAINT SKYBLUE (-1050 1700);
FORCEPROP 1 LAST VALUE 120K
J 2
(-1100 1700);
DISPLAY 0.723404 (-1100 1700);
PAINT SKYBLUE (-1100 1700);
FORCEPROP 1 LAST PACK_TYPE 0402LF
J 0
(-950 1700);
DISPLAY 0.723404 (-950 1700);
PAINT SKYBLUE (-950 1700);
FORCEPROP 2 LAST ROOM HSC1_BOM1
J 0
(-925 1825);
DISPLAY 1.021277 (-925 1825);
FORCEPROP 1 LAST LOCATION PR3982
J 0
(-1350 1775);
DISPLAY 0.723404 (-1350 1775);
PAINT AQUA (-1350 1775);
FORCEPROP 1 LASTPIN (-1175 1775) $PN 1
J 0
(-1163 1787);
DISPLAY 0.787234 (-1163 1787);
PAINT MONO (-1163 1787);
FORCEPROP 1 LASTPIN (-975 1775) $PN 2
J 0
(-1013 1787);
DISPLAY 0.787234 (-1013 1787);
PAINT MONO (-1013 1787);
FORCEPROP 2 LAST CDS_LIB pure_quanta
J 0
(-1075 1775);
DISPLAY INVISIBLE (-1075 1775);
FORCEPROP 1 LAST PATH I32
J 0
(-1125 1925);
DISPLAY 0.978723 (-1125 1925);
PAINT WHITE (-1125 1925);
DISPLAY INVISIBLE (-1125 1925);
FORCEPROP 0 LAST $SEC 1
J 0
(-1025 1850);
DISPLAY 0.680851 (-1025 1850);
PAINT MONO (-1025 1850);
DISPLAY INVISIBLE (-1025 1850);
FORCEPROP 0 LAST CDS_SEC 1
J 0
(-1025 1850);
DISPLAY 1.021277 (-1025 1850);
DISPLAY INVISIBLE (-1025 1850);
FORCEADD Q_RES..1
(-500 1600);
FORCEPROP 1 LAST PART_NUMBER CS00002JB13
J 0
(-825 1550);
DISPLAY 0.723404 (-825 1550);
PAINT WHITE (-825 1550);
DISPLAY INVISIBLE (-825 1550);
FORCEPROP 1 LAST TOLERANCE 5%
J 0
(-375 1550);
DISPLAY 0.723404 (-375 1550);
PAINT SKYBLUE (-375 1550);
FORCEPROP 1 LAST MATERIAL CHIP
J 0
(-325 1500);
DISPLAY 0.723404 (-325 1500);
PAINT SKYBLUE (-325 1500);
FORCEPROP 1 LAST WATTAGE 1/16W
J 2
(-625 1500);
DISPLAY 0.723404 (-625 1500);
PAINT SKYBLUE (-625 1500);
FORCEPROP 1 LAST VALUE 0
J 2
(-375 1625);
DISPLAY 0.723404 (-375 1625);
PAINT SKYBLUE (-375 1625);
FORCEPROP 1 LAST PACK_TYPE 0402LF
J 0
(-575 1500);
DISPLAY 0.723404 (-575 1500);
PAINT SKYBLUE (-575 1500);
FORCEPROP 2 LAST ROOM HSC1_BOM1
J 0
(-375 1675);
DISPLAY 1.021277 (-375 1675);
FORCEPROP 1 LAST LOCATION PR3988
J 0
(-800 1600);
DISPLAY 0.723404 (-800 1600);
PAINT AQUA (-800 1600);
FORCEPROP 1 LASTPIN (-600 1600) $PN 1
J 0
(-588 1612);
DISPLAY 0.787234 (-588 1612);
PAINT MONO (-588 1612);
FORCEPROP 1 LASTPIN (-400 1600) $PN 2
J 0
(-438 1612);
DISPLAY 0.787234 (-438 1612);
PAINT MONO (-438 1612);
FORCEPROP 2 LAST CDS_LIB pure_quanta
J 0
(-500 1600);
DISPLAY INVISIBLE (-500 1600);
FORCEPROP 1 LAST PATH I33
J 0
(-550 1750);
DISPLAY 0.978723 (-550 1750);
PAINT WHITE (-550 1750);
DISPLAY INVISIBLE (-550 1750);
FORCEPROP 0 LAST $SEC 1
J 0
(-375 1675);
DISPLAY 0.680851 (-375 1675);
PAINT MONO (-375 1675);
DISPLAY INVISIBLE (-375 1675);
FORCEPROP 0 LAST CDS_SEC 1
J 0
(-375 1675);
DISPLAY 1.021277 (-375 1675);
DISPLAY INVISIBLE (-375 1675);
FORCEADD Q_RES..2
(-125 950);
FORCEPROP 1 LAST PART_NUMBER CS22002BB07
J 0
(-75 850);
DISPLAY 0.723404 (-75 850);
PAINT WHITE (-75 850);
DISPLAY INVISIBLE (-75 850);
FORCEPROP 1 LAST TOLERANCE 0.1%
J 0
(-70 1000);
DISPLAY 0.723404 (-70 1000);
PAINT SKYBLUE (-70 1000);
FORCEPROP 1 LAST WATTAGE 1/16W
J 0
(-75 950);
DISPLAY 0.723404 (-75 950);
PAINT SKYBLUE (-75 950);
FORCEPROP 1 LAST VALUE 2K
J 0
(-70 1050);
DISPLAY 0.723404 (-70 1050);
PAINT SKYBLUE (-70 1050);
FORCEPROP 1 LAST MATERIAL CHIP
J 0
(-75 900);
DISPLAY 0.723404 (-75 900);
PAINT SKYBLUE (-75 900);
FORCEPROP 1 LAST PACK_TYPE 0402LF
J 0
(-75 800);
DISPLAY 0.723404 (-75 800);
PAINT SKYBLUE (-75 800);
FORCEPROP 2 LAST ROOM HSC1_BOM1
J 0
(-50 1150);
DISPLAY 1.021277 (-50 1150);
FORCEPROP 1 LAST LOCATION PR3990
J 0
(-70 1100);
DISPLAY 0.723404 (-70 1100);
PAINT AQUA (-70 1100);
FORCEPROP 1 LASTPIN (-125 1050) $PN 1
J 0
(-120 1012);
DISPLAY 0.787234 (-120 1012);
PAINT MONO (-120 1012);
FORCEPROP 1 LASTPIN (-125 850) $PN 2
J 0
(-120 860);
DISPLAY 0.787234 (-120 860);
PAINT MONO (-120 860);
FORCEPROP 2 LAST CDS_LIB pure_quanta
J 0
(-125 950);
DISPLAY INVISIBLE (-125 950);
FORCEPROP 1 LAST PATH I34
J 0
(-75 1125);
DISPLAY 0.978723 (-75 1125);
PAINT WHITE (-75 1125);
DISPLAY INVISIBLE (-75 1125);
FORCEPROP 0 LAST $SEC 1
J 0
(-50 1150);
DISPLAY 0.680851 (-50 1150);
PAINT MONO (-50 1150);
DISPLAY INVISIBLE (-50 1150);
FORCEPROP 0 LAST CDS_SEC 1
J 0
(-50 1150);
DISPLAY 1.021277 (-50 1150);
DISPLAY INVISIBLE (-50 1150);
FORCEADD MP5991GLUZ..1
(850 1700);
FORCEPROP 1 LAST PART_NUMBER AL005991A00
J 0
(525 2550);
DISPLAY 0.723404 (525 2550);
PAINT GREEN (525 2550);
DISPLAY INVISIBLE (525 2550);
FORCEPROP 2 LAST PART_TYPE SMLF
J 0
(525 2650);
DISPLAY 1.021277 (525 2650);
FORCEPROP 1 LAST MATERIAL IC
J 0
(525 2507);
DISPLAY 0.723404 (525 2507);
PAINT GREEN (525 2507);
FORCEPROP 2 LAST VALUE MP5991GLU-Z
J 0
(525 2600);
DISPLAY 1.021277 (525 2600);
FORCEPROP 2 LAST ROOM HSC1_BOM1
J 0
(525 2775);
DISPLAY 1.021277 (525 2775);
FORCEPROP 1 LAST LOCATION PU296
J 0
(525 2700);
DISPLAY 1.148936 (525 2700);
PAINT GREEN (525 2700);
FORCEPROP 2 LASTPIN (375 1275) $PN 23
J 2
(365 1285);
DISPLAY 0.680851 (365 1285);
PAINT MONO (365 1285);
FORCEPROP 2 LASTPIN (1325 1625) $PN 3
J 0
(1335 1635);
DISPLAY 0.680851 (1335 1635);
PAINT MONO (1335 1635);
FORCEPROP 2 LASTPIN (1325 1525) $PN 6
J 0
(1335 1535);
DISPLAY 0.680851 (1335 1535);
PAINT MONO (1335 1535);
FORCEPROP 2 LASTPIN (375 975) $PN 20
J 2
(365 985);
DISPLAY 0.680851 (365 985);
PAINT MONO (365 985);
FORCEPROP 2 LASTPIN (1325 1325) $PN 5
J 0
(1335 1335);
DISPLAY 0.680851 (1335 1335);
PAINT MONO (1335 1335);
FORCEPROP 2 LASTPIN (375 1175) $PN 22
J 2
(365 1185);
DISPLAY 0.680851 (365 1185);
PAINT MONO (365 1185);
FORCEPROP 2 LASTPIN (375 1775) $PN 8
J 2
(365 1785);
DISPLAY 0.680851 (365 1785);
PAINT MONO (365 1785);
FORCEPROP 2 LASTPIN (1325 1425) $PN 7
J 0
(1335 1435);
DISPLAY 0.680851 (1335 1435);
PAINT MONO (1335 1435);
FORCEPROP 2 LASTPIN (375 1375) $PN 24
J 2
(365 1385);
DISPLAY 0.680851 (365 1385);
PAINT MONO (365 1385);
FORCEPROP 2 LASTPIN (375 1475) $PN 4
J 2
(365 1485);
DISPLAY 0.680851 (365 1485);
PAINT MONO (365 1485);
FORCEPROP 2 LASTPIN (375 1675) $PN 17
J 2
(365 1685);
DISPLAY 0.680851 (365 1685);
PAINT MONO (365 1685);
FORCEPROP 2 LASTPIN (1325 1125) $PN 19
J 0
(1335 1135);
DISPLAY 0.680851 (1335 1135);
PAINT MONO (1335 1135);
FORCEPROP 2 LASTPIN (375 1875) $PN 21
J 2
(365 1885);
DISPLAY 0.680851 (365 1885);
PAINT MONO (365 1885);
FORCEPROP 2 LASTPIN (375 2425) $PN 9
J 2
(365 2435);
DISPLAY 0.680851 (365 2435);
PAINT MONO (365 2435);
FORCEPROP 2 LASTPIN (375 2375) $PN 10
J 2
(365 2385);
DISPLAY 0.680851 (365 2385);
PAINT MONO (365 2385);
FORCEPROP 2 LASTPIN (375 2325) $PN 11
J 2
(365 2335);
DISPLAY 0.680851 (365 2335);
PAINT MONO (365 2335);
FORCEPROP 2 LASTPIN (375 2275) $PN 12
J 2
(365 2285);
DISPLAY 0.680851 (365 2285);
PAINT MONO (365 2285);
FORCEPROP 2 LASTPIN (375 2225) $PN 13
J 2
(365 2235);
DISPLAY 0.680851 (365 2235);
PAINT MONO (365 2235);
FORCEPROP 2 LASTPIN (375 2175) $PN 14
J 2
(365 2185);
DISPLAY 0.680851 (365 2185);
PAINT MONO (365 2185);
FORCEPROP 2 LASTPIN (375 2125) $PN 15
J 2
(365 2135);
DISPLAY 0.680851 (365 2135);
PAINT MONO (365 2135);
FORCEPROP 2 LASTPIN (375 2075) $PN 16
J 2
(365 2085);
DISPLAY 0.680851 (365 2085);
PAINT MONO (365 2085);
FORCEPROP 2 LASTPIN (375 2025) $PN 33
J 2
(365 2035);
DISPLAY 0.680851 (365 2035);
PAINT MONO (365 2035);
FORCEPROP 2 LASTPIN (1325 2425) $PN 1
J 0
(1335 2435);
DISPLAY 0.680851 (1335 2435);
PAINT MONO (1335 2435);
FORCEPROP 2 LASTPIN (1325 2375) $PN 2
J 0
(1335 2385);
DISPLAY 0.680851 (1335 2385);
PAINT MONO (1335 2385);
FORCEPROP 2 LASTPIN (1325 2325) $PN 25
J 0
(1335 2335);
DISPLAY 0.680851 (1335 2335);
PAINT MONO (1335 2335);
FORCEPROP 2 LASTPIN (1325 2275) $PN 26
J 0
(1335 2285);
DISPLAY 0.680851 (1335 2285);
PAINT MONO (1335 2285);
FORCEPROP 2 LASTPIN (1325 2225) $PN 27
J 0
(1335 2235);
DISPLAY 0.680851 (1335 2235);
PAINT MONO (1335 2235);
FORCEPROP 2 LASTPIN (1325 2175) $PN 28
J 0
(1335 2185);
DISPLAY 0.680851 (1335 2185);
PAINT MONO (1335 2185);
FORCEPROP 2 LASTPIN (1325 2125) $PN 29
J 0
(1335 2135);
DISPLAY 0.680851 (1335 2135);
PAINT MONO (1335 2135);
FORCEPROP 2 LASTPIN (1325 2075) $PN 30
J 0
(1335 2085);
DISPLAY 0.680851 (1335 2085);
PAINT MONO (1335 2085);
FORCEPROP 2 LASTPIN (1325 2025) $PN 31
J 0
(1335 2035);
DISPLAY 0.680851 (1335 2035);
PAINT MONO (1335 2035);
FORCEPROP 2 LASTPIN (1325 1975) $PN 32
J 0
(1335 1985);
DISPLAY 0.680851 (1335 1985);
PAINT MONO (1335 1985);
FORCEPROP 2 LASTPIN (1325 1225) $PN 18
J 0
(1335 1235);
DISPLAY 0.680851 (1335 1235);
PAINT MONO (1335 1235);
FORCEPROP 2 LAST CDS_LIB pure_quanta
J 0
(850 1700);
DISPLAY INVISIBLE (850 1700);
FORCEPROP 1 LAST CDS_LMAN_SYM_OUTLINE -325,775,325,-775
J 0
(850 1700);
DISPLAY 0.468085 (850 1700);
PAINT GREEN (850 1700);
DISPLAY INVISIBLE (850 1700);
FORCEPROP 1 LAST NEEDS_NO_SIZE TRUE
J 0
(850 1700);
DISPLAY 0.723404 (850 1700);
PAINT GREEN (850 1700);
DISPLAY INVISIBLE (850 1700);
FORCEPROP 2 LAST SEC_TYPE 
J 0
(550 2925);
DISPLAY 1.021277 (550 2925);
DISPLAY INVISIBLE (550 2925);
FORCEPROP 1 LAST PATH I35
J 0
(850 1700);
DISPLAY 0.723404 (850 1700);
PAINT GREEN (850 1700);
DISPLAY INVISIBLE (850 1700);
FORCEPROP 2 LAST SEC 1
J 0
(550 2925);
DISPLAY 0.680851 (550 2925);
PAINT MONO (550 2925);
DISPLAY INVISIBLE (550 2925);
FORCEADD UNIVERSAL_POWER..1
(-125 2575);
FORCEPROP 3 LASTPIN (-125 2525) SIG_NAME P12V_PSU\g
J 0
(-115 2535);
DISPLAY 0.659574 (-115 2535);
PAINT MONO (-115 2535);
DISPLAY INVISIBLE (-115 2535);
FORCEPROP 1 LAST HDL_POWER P12V_PSU
J 1
(-125 2625);
DISPLAY 0.723404 (-125 2625);
PAINT GREEN (-125 2625);
FORCEPROP 2 LAST ROOM AUX_SW
J 0
(-125 2675);
DISPLAY 0.617021 (-125 2675);
DISPLAY INVISIBLE (-125 2675);
FORCEPROP 2 LAST CDS_LIB logical_power
J 0
(-125 2575);
DISPLAY INVISIBLE (-125 2575);
FORCEPROP 2 LAST BOM_COST MIO_VRD_SB
J 0
(-125 2675);
DISPLAY 0.617021 (-125 2675);
PAINT PURPLE (-125 2675);
DISPLAY INVISIBLE (-125 2675);
FORCEPROP 1 LAST PATH I36
J 0
(-75 2600);
DISPLAY 0.872340 (-75 2600);
PAINT AQUA (-75 2600);
DISPLAY INVISIBLE (-75 2600);
FORCEADD UNIVERSAL_GND..1
(1825 -2025);
FORCEPROP 3 LASTPIN (1825 -1975) SIG_NAME AGND_HSC\g
J 0
(1835 -1965);
DISPLAY 0.659574 (1835 -1965);
PAINT MONO (1835 -1965);
DISPLAY INVISIBLE (1835 -1965);
FORCEPROP 1 LAST HDL_POWER AGND_HSC
J 1
(1850 -2100);
DISPLAY 0.723404 (1850 -2100);
PAINT GREEN (1850 -2100);
FORCEPROP 2 LAST CDS_LIB logical_power
J 0
(1825 -2025);
DISPLAY INVISIBLE (1825 -2025);
FORCEPROP 1 LAST PATH I37
J 0
(1900 -2025);
DISPLAY 0.872340 (1900 -2025);
PAINT AQUA (1900 -2025);
DISPLAY INVISIBLE (1900 -2025);
FORCEADD Q_CAP..1
(1825 -1800);
FORCEPROP 1 LAST PART_NUMBER CH3683K1B09
J 0
(1875 -1925);
DISPLAY 0.723404 (1875 -1925);
PAINT WHITE (1875 -1925);
DISPLAY INVISIBLE (1875 -1925);
FORCEPROP 1 LAST VOLTAGE 16V
J 0
(1875 -1825);
DISPLAY 0.723404 (1875 -1825);
PAINT SKYBLUE (1875 -1825);
FORCEPROP 1 LAST VALUE 0.068UF
J 0
(1875 -1775);
DISPLAY 0.723404 (1875 -1775);
PAINT SKYBLUE (1875 -1775);
FORCEPROP 2 LAST ROOM HSC1_BOM1
J 0
(1900 -2025);
DISPLAY 1.021277 (1900 -2025);
FORCEPROP 1 LAST PACK_TYPE 0402
J 0
(1875 -1975);
DISPLAY 0.723404 (1875 -1975);
PAINT SKYBLUE (1875 -1975);
FORCEPROP 1 LAST MATERIAL X7R
J 0
(1875 -1875);
DISPLAY 0.723404 (1875 -1875);
PAINT SKYBLUE (1875 -1875);
FORCEPROP 1 LAST LOCATION PC2227
J 0
(1875 -1725);
DISPLAY 0.723404 (1875 -1725);
PAINT AQUA (1875 -1725);
FORCEPROP 1 LASTPIN (1825 -1700) $PN 1
J 0
(1835 -1720);
DISPLAY 0.787234 (1835 -1720);
PAINT MONO (1835 -1720);
FORCEPROP 1 LASTPIN (1825 -1900) $PN 2
J 0
(1835 -1920);
DISPLAY 0.787234 (1835 -1920);
PAINT MONO (1835 -1920);
FORCEPROP 1 LAST TOLERANCE 10%
J 0
(1875 -1850);
DISPLAY 0.978723 (1875 -1850);
PAINT SKYBLUE (1875 -1850);
DISPLAY INVISIBLE (1875 -1850);
FORCEPROP 2 LAST CDS_LIB pure_quanta
J 0
(1825 -1800);
DISPLAY INVISIBLE (1825 -1800);
FORCEPROP 1 LAST PATH I38
J 0
(1875 -1650);
DISPLAY 0.978723 (1875 -1650);
PAINT WHITE (1875 -1650);
DISPLAY INVISIBLE (1875 -1650);
FORCEPROP 0 LAST $SEC 1
J 0
(1875 -1675);
DISPLAY 0.680851 (1875 -1675);
PAINT MONO (1875 -1675);
DISPLAY INVISIBLE (1875 -1675);
FORCEPROP 0 LAST CDS_SEC 1
J 0
(1875 -1675);
DISPLAY 1.021277 (1875 -1675);
DISPLAY INVISIBLE (1875 -1675);
FORCEADD Q_RES..1
(2325 -1250);
FORCEPROP 1 LAST PART_NUMBER CS00002JB13
J 0
(2000 -1300);
DISPLAY 0.723404 (2000 -1300);
PAINT WHITE (2000 -1300);
DISPLAY INVISIBLE (2000 -1300);
FORCEPROP 1 LAST VALUE 0
J 2
(2475 -1225);
DISPLAY 0.723404 (2475 -1225);
PAINT SKYBLUE (2475 -1225);
FORCEPROP 1 LAST WATTAGE 1/16W
J 2
(2200 -1350);
DISPLAY 0.723404 (2200 -1350);
PAINT SKYBLUE (2200 -1350);
FORCEPROP 1 LAST PACK_TYPE 0402LF
J 0
(2250 -1350);
DISPLAY 0.723404 (2250 -1350);
PAINT SKYBLUE (2250 -1350);
FORCEPROP 1 LAST TOLERANCE 5%
J 0
(2450 -1300);
DISPLAY 0.723404 (2450 -1300);
PAINT SKYBLUE (2450 -1300);
FORCEPROP 1 LAST MATERIAL CHIP
J 0
(2500 -1350);
DISPLAY 0.723404 (2500 -1350);
PAINT SKYBLUE (2500 -1350);
FORCEPROP 2 LAST ROOM HSC1_BOM1
J 0
(2100 -1400);
DISPLAY 1.021277 (2100 -1400);
FORCEPROP 1 LAST LOCATION PR3995
J 0
(2025 -1250);
DISPLAY 0.723404 (2025 -1250);
PAINT AQUA (2025 -1250);
FORCEPROP 1 LASTPIN (2225 -1250) $PN 1
J 0
(2237 -1238);
DISPLAY 0.787234 (2237 -1238);
PAINT MONO (2237 -1238);
FORCEPROP 1 LASTPIN (2425 -1250) $PN 2
J 0
(2387 -1238);
DISPLAY 0.787234 (2387 -1238);
PAINT MONO (2387 -1238);
FORCEPROP 2 LAST CDS_LIB pure_quanta
J 0
(2325 -1250);
DISPLAY INVISIBLE (2325 -1250);
FORCEPROP 1 LAST PATH I39
J 0
(2275 -1100);
DISPLAY 0.978723 (2275 -1100);
PAINT WHITE (2275 -1100);
DISPLAY INVISIBLE (2275 -1100);
FORCEPROP 0 LAST $SEC 1
J 0
(2475 -1175);
DISPLAY 0.680851 (2475 -1175);
PAINT MONO (2475 -1175);
DISPLAY INVISIBLE (2475 -1175);
FORCEPROP 0 LAST CDS_SEC 1
J 0
(2475 -1175);
DISPLAY 1.021277 (2475 -1175);
DISPLAY INVISIBLE (2475 -1175);
FORCEADD Q_CAP..1
(-2750 -1175);
FORCEPROP 1 LAST PART_NUMBER CH5104KEB02
J 0
(-2675 -1225);
DISPLAY 0.723404 (-2675 -1225);
PAINT WHITE (-2675 -1225);
DISPLAY INVISIBLE (-2675 -1225);
FORCEPROP 1 LAST MATERIAL X6S
J 0
(-2675 -1175);
DISPLAY 0.723404 (-2675 -1175);
PAINT SKYBLUE (-2675 -1175);
FORCEPROP 1 LAST VOLTAGE 25V
J 0
(-2675 -1125);
DISPLAY 0.723404 (-2675 -1125);
PAINT SKYBLUE (-2675 -1125);
FORCEPROP 1 LAST VALUE 1UF
J 0
(-2675 -1075);
DISPLAY 0.723404 (-2675 -1075);
PAINT SKYBLUE (-2675 -1075);
FORCEPROP 1 LAST PACK_TYPE C0402
J 0
(-2675 -1275);
DISPLAY 0.723404 (-2675 -1275);
PAINT SKYBLUE (-2675 -1275);
FORCEPROP 2 LAST ROOM HSC1_BOM1
J 0
(-2675 -975);
DISPLAY 1.021277 (-2675 -975);
FORCEPROP 1 LAST LOCATION PC2223
J 0
(-2675 -1025);
DISPLAY 0.723404 (-2675 -1025);
PAINT AQUA (-2675 -1025);
FORCEPROP 1 LASTPIN (-2750 -1075) $PN 1
J 0
(-2740 -1095);
DISPLAY 0.787234 (-2740 -1095);
PAINT MONO (-2740 -1095);
FORCEPROP 1 LASTPIN (-2750 -1275) $PN 2
J 0
(-2740 -1295);
DISPLAY 0.787234 (-2740 -1295);
PAINT MONO (-2740 -1295);
FORCEPROP 1 LAST PATH I4
J 0
(-2700 -1025);
DISPLAY 0.978723 (-2700 -1025);
PAINT WHITE (-2700 -1025);
DISPLAY INVISIBLE (-2700 -1025);
FORCEPROP 1 LAST TOLERANCE 10%
J 0
(-2700 -1225);
DISPLAY 0.978723 (-2700 -1225);
PAINT SKYBLUE (-2700 -1225);
DISPLAY INVISIBLE (-2700 -1225);
FORCEPROP 2 LAST CDS_LIB pure_quanta
J 0
(-2750 -1175);
DISPLAY INVISIBLE (-2750 -1175);
FORCEPROP 0 LAST $SEC 1
J 0
(-2675 -975);
DISPLAY 0.680851 (-2675 -975);
PAINT MONO (-2675 -975);
DISPLAY INVISIBLE (-2675 -975);
FORCEPROP 0 LAST CDS_SEC 1
J 0
(-2675 -975);
DISPLAY 1.021277 (-2675 -975);
DISPLAY INVISIBLE (-2675 -975);
FORCEADD Q_RES..1
(2325 -1075);
FORCEPROP 1 LAST PART_NUMBER CS00002JB13
J 0
(2000 -1125);
DISPLAY 0.723404 (2000 -1125);
PAINT WHITE (2000 -1125);
DISPLAY INVISIBLE (2000 -1125);
FORCEPROP 1 LAST MATERIAL CHIP
J 0
(2500 -1175);
DISPLAY 0.723404 (2500 -1175);
PAINT SKYBLUE (2500 -1175);
FORCEPROP 1 LAST WATTAGE 1/16W
J 2
(2200 -1175);
DISPLAY 0.723404 (2200 -1175);
PAINT SKYBLUE (2200 -1175);
FORCEPROP 1 LAST PACK_TYPE 0402LF
J 0
(2250 -1175);
DISPLAY 0.723404 (2250 -1175);
PAINT SKYBLUE (2250 -1175);
FORCEPROP 2 LAST ROOM HSC1_BOM1
J 0
(2150 -975);
DISPLAY 1.021277 (2150 -975);
FORCEPROP 1 LAST VALUE 0
J 2
(2475 -1050);
DISPLAY 0.723404 (2475 -1050);
PAINT SKYBLUE (2475 -1050);
FORCEPROP 1 LAST TOLERANCE 5%
J 0
(2450 -1125);
DISPLAY 0.723404 (2450 -1125);
PAINT SKYBLUE (2450 -1125);
FORCEPROP 1 LAST LOCATION PR3994
J 0
(2025 -1075);
DISPLAY 0.723404 (2025 -1075);
PAINT AQUA (2025 -1075);
FORCEPROP 1 LASTPIN (2225 -1075) $PN 1
J 0
(2237 -1063);
DISPLAY 0.787234 (2237 -1063);
PAINT MONO (2237 -1063);
FORCEPROP 1 LASTPIN (2425 -1075) $PN 2
J 0
(2387 -1063);
DISPLAY 0.787234 (2387 -1063);
PAINT MONO (2387 -1063);
FORCEPROP 2 LAST CDS_LIB pure_quanta
J 0
(2325 -1075);
DISPLAY INVISIBLE (2325 -1075);
FORCEPROP 1 LAST PATH I40
J 0
(2275 -925);
DISPLAY 0.978723 (2275 -925);
PAINT WHITE (2275 -925);
DISPLAY INVISIBLE (2275 -925);
FORCEPROP 0 LAST $SEC 1
J 0
(2475 -1000);
DISPLAY 0.680851 (2475 -1000);
PAINT MONO (2475 -1000);
DISPLAY INVISIBLE (2475 -1000);
FORCEPROP 0 LAST CDS_SEC 1
J 0
(2475 -1000);
DISPLAY 1.021277 (2475 -1000);
DISPLAY INVISIBLE (2475 -1000);
FORCEADD UNIVERSAL_POWER..1
(1950 -200);
FORCEPROP 3 LASTPIN (1950 -250) SIG_NAME P12V_AUX\g
J 0
(1960 -240);
DISPLAY 0.659574 (1960 -240);
PAINT MONO (1960 -240);
DISPLAY INVISIBLE (1960 -240);
FORCEPROP 1 LAST HDL_POWER P12V_AUX
J 1
(1950 -150);
DISPLAY 0.723404 (1950 -150);
PAINT GREEN (1950 -150);
FORCEPROP 2 LAST ROOM AUX_SW
J 0
(1950 -100);
DISPLAY 0.617021 (1950 -100);
DISPLAY INVISIBLE (1950 -100);
FORCEPROP 2 LAST CDS_LIB logical_power
J 0
(1950 -200);
DISPLAY INVISIBLE (1950 -200);
FORCEPROP 2 LAST BOM_COST MIO_VRD_SB
J 0
(1950 -100);
DISPLAY 0.617021 (1950 -100);
PAINT PURPLE (1950 -100);
DISPLAY INVISIBLE (1950 -100);
FORCEPROP 1 LAST PATH I41
J 0
(2000 -175);
DISPLAY 0.872340 (2000 -175);
PAINT AQUA (2000 -175);
DISPLAY INVISIBLE (2000 -175);
FORCEADD OFFPAGE..4
(3100 -1650);
FORCEPROP 2 LAST $XR2 303 
J 0
(3526 -1650);
DISPLAY 0.638298 (3526 -1650);
PAINT MONO (3526 -1650);
FORCEPROP 2 LAST $XR1 302 
J 0
(3406 -1650);
DISPLAY 0.638298 (3406 -1650);
PAINT MONO (3406 -1650);
FORCEPROP 2 LAST $XR0 301 
J 0
(3286 -1650);
DISPLAY 0.638298 (3286 -1650);
PAINT MONO (3286 -1650);
FORCEPROP 1 LAST COMMENT_BODY TRUE
J 0
(3075 -1750);
DISPLAY 0.872340 (3075 -1750);
PAINT GREEN (3075 -1750);
DISPLAY INVISIBLE (3075 -1750);
FORCEPROP 1 LAST OFFPAGE TRUE
J 0
(3425 -1775);
DISPLAY 0.872340 (3425 -1775);
PAINT GREEN (3425 -1775);
DISPLAY INVISIBLE (3425 -1775);
FORCEPROP 2 LAST CDS_LIB standard
J 0
(3100 -1650);
DISPLAY INVISIBLE (3100 -1650);
FORCEPROP 2 LAST PATH I42
J 0
(3550 -1600);
DISPLAY 1.021277 (3550 -1600);
DISPLAY INVISIBLE (3550 -1600);
FORCEADD OFFPAGE..5
R 2
(3100 -1550);
FORCEPROP 2 LAST $XR2 301 
J 0
(3529 -1550);
DISPLAY 0.638298 (3529 -1550);
PAINT MONO (3529 -1550);
FORCEPROP 2 LAST $XR1 303 
J 0
(3409 -1550);
DISPLAY 0.638298 (3409 -1550);
PAINT MONO (3409 -1550);
FORCEPROP 2 LAST $XR0 302 
J 0
(3289 -1550);
DISPLAY 0.638298 (3289 -1550);
PAINT MONO (3289 -1550);
FORCEPROP 1 LAST COMMENT_BODY TRUE
J 2
(3000 -1625);
DISPLAY 1.170213 (3000 -1625);
PAINT GREEN (3000 -1625);
DISPLAY INVISIBLE (3000 -1625);
FORCEPROP 1 LAST OFFPAGE TRUE
J 2
(2775 -1675);
DISPLAY 0.872340 (2775 -1675);
PAINT AQUA (2775 -1675);
DISPLAY INVISIBLE (2775 -1675);
FORCEPROP 2 LAST CDS_LIB standard
J 2
(3100 -1550);
DISPLAY INVISIBLE (3100 -1550);
FORCEPROP 2 LAST PATH I43
J 0
(3550 -1500);
DISPLAY 1.021277 (3550 -1500);
DISPLAY INVISIBLE (3550 -1500);
FORCEADD OFFPAGE..5
R 2
(3100 -1450);
FORCEPROP 2 LAST $XR2 301 
J 0
(3529 -1450);
DISPLAY 0.638298 (3529 -1450);
PAINT MONO (3529 -1450);
FORCEPROP 2 LAST $XR1 303 
J 0
(3409 -1450);
DISPLAY 0.638298 (3409 -1450);
PAINT MONO (3409 -1450);
FORCEPROP 2 LAST $XR0 302 
J 0
(3289 -1450);
DISPLAY 0.638298 (3289 -1450);
PAINT MONO (3289 -1450);
FORCEPROP 1 LAST COMMENT_BODY TRUE
J 2
(3000 -1525);
DISPLAY 1.170213 (3000 -1525);
PAINT GREEN (3000 -1525);
DISPLAY INVISIBLE (3000 -1525);
FORCEPROP 1 LAST OFFPAGE TRUE
J 2
(2775 -1575);
DISPLAY 0.872340 (2775 -1575);
PAINT AQUA (2775 -1575);
DISPLAY INVISIBLE (2775 -1575);
FORCEPROP 2 LAST CDS_LIB standard
J 2
(3100 -1450);
DISPLAY INVISIBLE (3100 -1450);
FORCEPROP 2 LAST PATH I44
J 0
(3550 -1400);
DISPLAY 1.021277 (3550 -1400);
DISPLAY INVISIBLE (3550 -1400);
FORCEADD OFFPAGE..4
(3100 -1250);
FORCEPROP 2 LAST $XR2 303 
J 0
(3526 -1250);
DISPLAY 0.638298 (3526 -1250);
PAINT MONO (3526 -1250);
FORCEPROP 2 LAST $XR1 302 
J 0
(3406 -1250);
DISPLAY 0.638298 (3406 -1250);
PAINT MONO (3406 -1250);
FORCEPROP 2 LAST $XR0 301 
J 0
(3286 -1250);
DISPLAY 0.638298 (3286 -1250);
PAINT MONO (3286 -1250);
FORCEPROP 1 LAST COMMENT_BODY TRUE
J 0
(3075 -1350);
DISPLAY 0.872340 (3075 -1350);
PAINT GREEN (3075 -1350);
DISPLAY INVISIBLE (3075 -1350);
FORCEPROP 1 LAST OFFPAGE TRUE
J 0
(3425 -1375);
DISPLAY 0.872340 (3425 -1375);
PAINT GREEN (3425 -1375);
DISPLAY INVISIBLE (3425 -1375);
FORCEPROP 2 LAST CDS_LIB standard
J 0
(3100 -1250);
DISPLAY INVISIBLE (3100 -1250);
FORCEPROP 2 LAST PATH I45
J 0
(3550 -1200);
DISPLAY 1.021277 (3550 -1200);
DISPLAY INVISIBLE (3550 -1200);
FORCEADD OFFPAGE..5
R 2
(3100 -1075);
FORCEPROP 2 LAST $XR2 301 
J 0
(3529 -1075);
DISPLAY 0.638298 (3529 -1075);
PAINT MONO (3529 -1075);
FORCEPROP 2 LAST $XR1 303 
J 0
(3409 -1075);
DISPLAY 0.638298 (3409 -1075);
PAINT MONO (3409 -1075);
FORCEPROP 2 LAST $XR0 302 
J 0
(3289 -1075);
DISPLAY 0.638298 (3289 -1075);
PAINT MONO (3289 -1075);
FORCEPROP 1 LAST COMMENT_BODY TRUE
J 2
(3000 -1150);
DISPLAY 1.170213 (3000 -1150);
PAINT GREEN (3000 -1150);
DISPLAY INVISIBLE (3000 -1150);
FORCEPROP 1 LAST OFFPAGE TRUE
J 2
(2775 -1200);
DISPLAY 0.872340 (2775 -1200);
PAINT AQUA (2775 -1200);
DISPLAY INVISIBLE (2775 -1200);
FORCEPROP 2 LAST CDS_LIB standard
J 0
(3100 -1075);
DISPLAY INVISIBLE (3100 -1075);
FORCEPROP 2 LAST PATH I46
J 0
(3550 -1025);
DISPLAY 1.021277 (3550 -1025);
DISPLAY INVISIBLE (3550 -1025);
FORCEADD UNIVERSAL_GND..1
(1825 750);
FORCEPROP 3 LASTPIN (1825 800) SIG_NAME AGND_HSC\g
J 0
(1835 810);
DISPLAY 0.659574 (1835 810);
PAINT MONO (1835 810);
DISPLAY INVISIBLE (1835 810);
FORCEPROP 1 LAST HDL_POWER AGND_HSC
J 1
(1850 675);
DISPLAY 0.723404 (1850 675);
PAINT GREEN (1850 675);
FORCEPROP 2 LAST CDS_LIB logical_power
J 0
(1825 750);
DISPLAY INVISIBLE (1825 750);
FORCEPROP 1 LAST PATH I47
J 0
(1900 750);
DISPLAY 0.872340 (1900 750);
PAINT AQUA (1900 750);
DISPLAY INVISIBLE (1900 750);
FORCEADD Q_CAP..1
(1825 975);
FORCEPROP 1 LAST PART_NUMBER CH3683K1B09
J 0
(1875 850);
DISPLAY 0.723404 (1875 850);
PAINT WHITE (1875 850);
DISPLAY INVISIBLE (1875 850);
FORCEPROP 1 LAST VOLTAGE 16V
J 0
(1875 950);
DISPLAY 0.723404 (1875 950);
PAINT SKYBLUE (1875 950);
FORCEPROP 1 LAST PACK_TYPE 0402
J 0
(1875 800);
DISPLAY 0.723404 (1875 800);
PAINT SKYBLUE (1875 800);
FORCEPROP 1 LAST MATERIAL X7R
J 0
(1875 900);
DISPLAY 0.723404 (1875 900);
PAINT SKYBLUE (1875 900);
FORCEPROP 1 LAST VALUE 0.068UF
J 0
(1875 1000);
DISPLAY 0.723404 (1875 1000);
PAINT SKYBLUE (1875 1000);
FORCEPROP 2 LAST ROOM HSC1_BOM1
J 0
(1875 1100);
DISPLAY 1.021277 (1875 1100);
FORCEPROP 1 LAST LOCATION PC2226
J 0
(1875 1050);
DISPLAY 0.723404 (1875 1050);
PAINT AQUA (1875 1050);
FORCEPROP 1 LASTPIN (1825 1075) $PN 1
J 0
(1835 1055);
DISPLAY 0.787234 (1835 1055);
PAINT MONO (1835 1055);
FORCEPROP 1 LASTPIN (1825 875) $PN 2
J 0
(1835 855);
DISPLAY 0.787234 (1835 855);
PAINT MONO (1835 855);
FORCEPROP 1 LAST TOLERANCE 10%
J 0
(1875 925);
DISPLAY 0.978723 (1875 925);
PAINT SKYBLUE (1875 925);
DISPLAY INVISIBLE (1875 925);
FORCEPROP 2 LAST CDS_LIB pure_quanta
J 0
(1825 975);
DISPLAY INVISIBLE (1825 975);
FORCEPROP 1 LAST PATH I48
J 0
(1875 1125);
DISPLAY 0.978723 (1875 1125);
PAINT WHITE (1875 1125);
DISPLAY INVISIBLE (1875 1125);
FORCEPROP 0 LAST $SEC 1
J 0
(1875 1100);
DISPLAY 0.680851 (1875 1100);
PAINT MONO (1875 1100);
DISPLAY INVISIBLE (1875 1100);
FORCEPROP 0 LAST CDS_SEC 1
J 0
(1875 1100);
DISPLAY 1.021277 (1875 1100);
DISPLAY INVISIBLE (1875 1100);
FORCEADD Q_RES..1
(2325 1525);
FORCEPROP 1 LAST PART_NUMBER CS00002JB13
J 0
(2000 1475);
DISPLAY 0.723404 (2000 1475);
PAINT WHITE (2000 1475);
DISPLAY INVISIBLE (2000 1475);
FORCEPROP 1 LAST TOLERANCE 5%
J 0
(2450 1475);
DISPLAY 0.723404 (2450 1475);
PAINT SKYBLUE (2450 1475);
FORCEPROP 1 LAST MATERIAL CHIP
J 0
(2500 1425);
DISPLAY 0.723404 (2500 1425);
PAINT SKYBLUE (2500 1425);
FORCEPROP 1 LAST VALUE 0
J 2
(2475 1550);
DISPLAY 0.723404 (2475 1550);
PAINT SKYBLUE (2475 1550);
FORCEPROP 1 LAST PACK_TYPE 0402LF
J 0
(2250 1425);
DISPLAY 0.723404 (2250 1425);
PAINT SKYBLUE (2250 1425);
FORCEPROP 1 LAST WATTAGE 1/16W
J 2
(2200 1425);
DISPLAY 0.723404 (2200 1425);
PAINT SKYBLUE (2200 1425);
FORCEPROP 2 LAST ROOM HSC1_BOM1
J 0
(2475 1600);
DISPLAY 1.021277 (2475 1600);
FORCEPROP 1 LAST LOCATION PR3993
J 0
(2025 1525);
DISPLAY 0.723404 (2025 1525);
PAINT AQUA (2025 1525);
FORCEPROP 1 LASTPIN (2225 1525) $PN 1
J 0
(2237 1537);
DISPLAY 0.787234 (2237 1537);
PAINT MONO (2237 1537);
FORCEPROP 1 LASTPIN (2425 1525) $PN 2
J 0
(2387 1537);
DISPLAY 0.787234 (2387 1537);
PAINT MONO (2387 1537);
FORCEPROP 2 LAST CDS_LIB pure_quanta
J 0
(2325 1525);
DISPLAY INVISIBLE (2325 1525);
FORCEPROP 1 LAST PATH I49
J 0
(2275 1675);
DISPLAY 0.978723 (2275 1675);
PAINT WHITE (2275 1675);
DISPLAY INVISIBLE (2275 1675);
FORCEPROP 0 LAST $SEC 1
J 0
(2475 1600);
DISPLAY 0.680851 (2475 1600);
PAINT MONO (2475 1600);
DISPLAY INVISIBLE (2475 1600);
FORCEPROP 0 LAST CDS_SEC 1
J 0
(2475 1600);
DISPLAY 1.021277 (2475 1600);
DISPLAY INVISIBLE (2475 1600);
FORCEADD Q_RES..1
R 1
(-2750 -700);
FORCEPROP 1 LAST PART_NUMBER CS00002JB13
J 0
(-2675 -800);
DISPLAY 0.723404 (-2675 -800);
PAINT WHITE (-2675 -800);
DISPLAY INVISIBLE (-2675 -800);
FORCEPROP 1 LAST VALUE 0
R 2
J 0
(-2650 -575);
DISPLAY 0.723404 (-2650 -575);
PAINT SKYBLUE (-2650 -575);
FORCEPROP 1 LAST PACK_TYPE 0402LF
J 0
(-2675 -850);
DISPLAY 0.723404 (-2675 -850);
PAINT SKYBLUE (-2675 -850);
FORCEPROP 1 LAST WATTAGE 1/16W
J 0
(-2675 -750);
DISPLAY 0.723404 (-2675 -750);
PAINT SKYBLUE (-2675 -750);
FORCEPROP 1 LAST MATERIAL CHIP
J 0
(-2675 -700);
DISPLAY 0.787234 (-2675 -700);
PAINT SKYBLUE (-2675 -700);
FORCEPROP 1 LAST TOLERANCE 5%
J 0
(-2675 -650);
DISPLAY 0.723404 (-2675 -650);
PAINT SKYBLUE (-2675 -650);
FORCEPROP 2 LAST ROOM HSC1_BOM1
J 0
(-2675 -500);
DISPLAY 1.021277 (-2675 -500);
FORCEPROP 1 LAST LOCATION PR3981
J 0
(-2675 -550);
DISPLAY 0.723404 (-2675 -550);
PAINT AQUA (-2675 -550);
FORCEPROP 1 LASTPIN (-2750 -800) $PN 1
R 1
J 0
(-2762 -788);
DISPLAY 0.787234 (-2762 -788);
PAINT MONO (-2762 -788);
FORCEPROP 1 LASTPIN (-2750 -600) $PN 2
R 1
J 0
(-2762 -638);
DISPLAY 0.787234 (-2762 -638);
PAINT MONO (-2762 -638);
FORCEPROP 2 LAST CDS_LIB pure_quanta
J 0
(-2750 -700);
DISPLAY INVISIBLE (-2750 -700);
FORCEPROP 1 LAST PATH I5
R 1
J 0
(-2900 -750);
DISPLAY 0.978723 (-2900 -750);
PAINT WHITE (-2900 -750);
DISPLAY INVISIBLE (-2900 -750);
FORCEPROP 0 LAST $SEC 1
R 1
J 0
(-2675 -500);
DISPLAY 0.680851 (-2675 -500);
PAINT MONO (-2675 -500);
DISPLAY INVISIBLE (-2675 -500);
FORCEPROP 0 LAST CDS_SEC 1
R 1
J 0
(-2675 -500);
DISPLAY 1.021277 (-2675 -500);
DISPLAY INVISIBLE (-2675 -500);
FORCEADD Q_RES..1
(2325 1700);
FORCEPROP 1 LAST PART_NUMBER CS00002JB13
J 0
(2000 1650);
DISPLAY 0.723404 (2000 1650);
PAINT WHITE (2000 1650);
DISPLAY INVISIBLE (2000 1650);
FORCEPROP 1 LAST VALUE 0
J 2
(2475 1725);
DISPLAY 0.723404 (2475 1725);
PAINT SKYBLUE (2475 1725);
FORCEPROP 1 LAST MATERIAL CHIP
J 0
(2500 1600);
DISPLAY 0.723404 (2500 1600);
PAINT SKYBLUE (2500 1600);
FORCEPROP 1 LAST TOLERANCE 5%
J 0
(2450 1650);
DISPLAY 0.723404 (2450 1650);
PAINT SKYBLUE (2450 1650);
FORCEPROP 1 LAST WATTAGE 1/16W
J 2
(2200 1600);
DISPLAY 0.723404 (2200 1600);
PAINT SKYBLUE (2200 1600);
FORCEPROP 1 LAST PACK_TYPE 0402LF
J 0
(2250 1600);
DISPLAY 0.723404 (2250 1600);
PAINT SKYBLUE (2250 1600);
FORCEPROP 2 LAST ROOM HSC1_BOM1
J 0
(2475 1775);
DISPLAY 1.021277 (2475 1775);
FORCEPROP 1 LAST LOCATION PR3992
J 0
(2025 1700);
DISPLAY 0.723404 (2025 1700);
PAINT AQUA (2025 1700);
FORCEPROP 1 LASTPIN (2225 1700) $PN 1
J 0
(2237 1712);
DISPLAY 0.787234 (2237 1712);
PAINT MONO (2237 1712);
FORCEPROP 1 LASTPIN (2425 1700) $PN 2
J 0
(2387 1712);
DISPLAY 0.787234 (2387 1712);
PAINT MONO (2387 1712);
FORCEPROP 2 LAST CDS_LIB pure_quanta
J 0
(2325 1700);
DISPLAY INVISIBLE (2325 1700);
FORCEPROP 1 LAST PATH I50
J 0
(2275 1850);
DISPLAY 0.978723 (2275 1850);
PAINT WHITE (2275 1850);
DISPLAY INVISIBLE (2275 1850);
FORCEPROP 0 LAST $SEC 1
J 0
(2475 1775);
DISPLAY 0.680851 (2475 1775);
PAINT MONO (2475 1775);
DISPLAY INVISIBLE (2475 1775);
FORCEPROP 0 LAST CDS_SEC 1
J 0
(2475 1775);
DISPLAY 1.021277 (2475 1775);
DISPLAY INVISIBLE (2475 1775);
FORCEADD UNIVERSAL_POWER..1
(1950 2575);
FORCEPROP 3 LASTPIN (1950 2525) SIG_NAME P12V_AUX\g
J 0
(1960 2535);
DISPLAY 0.659574 (1960 2535);
PAINT MONO (1960 2535);
DISPLAY INVISIBLE (1960 2535);
FORCEPROP 1 LAST HDL_POWER P12V_AUX
J 1
(1950 2625);
DISPLAY 0.723404 (1950 2625);
PAINT GREEN (1950 2625);
FORCEPROP 2 LAST ROOM AUX_SW
J 0
(1950 2675);
DISPLAY 0.617021 (1950 2675);
DISPLAY INVISIBLE (1950 2675);
FORCEPROP 2 LAST CDS_LIB logical_power
J 0
(1950 2575);
DISPLAY INVISIBLE (1950 2575);
FORCEPROP 2 LAST BOM_COST MIO_VRD_SB
J 0
(1950 2675);
DISPLAY 0.617021 (1950 2675);
PAINT PURPLE (1950 2675);
DISPLAY INVISIBLE (1950 2675);
FORCEPROP 1 LAST PATH I51
J 0
(2000 2600);
DISPLAY 0.872340 (2000 2600);
PAINT AQUA (2000 2600);
DISPLAY INVISIBLE (2000 2600);
FORCEADD OFFPAGE..4
(3125 1125);
FORCEPROP 2 LAST $XR2 303 
J 0
(3551 1125);
DISPLAY 0.638298 (3551 1125);
PAINT MONO (3551 1125);
FORCEPROP 2 LAST $XR1 302 
J 0
(3431 1125);
DISPLAY 0.638298 (3431 1125);
PAINT MONO (3431 1125);
FORCEPROP 2 LAST $XR0 301 
J 0
(3311 1125);
DISPLAY 0.638298 (3311 1125);
PAINT MONO (3311 1125);
FORCEPROP 1 LAST COMMENT_BODY TRUE
J 0
(3100 1025);
DISPLAY 0.872340 (3100 1025);
PAINT GREEN (3100 1025);
DISPLAY INVISIBLE (3100 1025);
FORCEPROP 1 LAST OFFPAGE TRUE
J 0
(3450 1000);
DISPLAY 0.872340 (3450 1000);
PAINT GREEN (3450 1000);
DISPLAY INVISIBLE (3450 1000);
FORCEPROP 2 LAST CDS_LIB standard
J 0
(3125 1125);
DISPLAY INVISIBLE (3125 1125);
FORCEPROP 2 LAST PATH I52
J 0
(3575 1175);
DISPLAY 1.021277 (3575 1175);
DISPLAY INVISIBLE (3575 1175);
FORCEADD OFFPAGE..5
R 2
(3125 1225);
FORCEPROP 2 LAST $XR2 301 
J 0
(3554 1225);
DISPLAY 0.638298 (3554 1225);
PAINT MONO (3554 1225);
FORCEPROP 2 LAST $XR1 303 
J 0
(3434 1225);
DISPLAY 0.638298 (3434 1225);
PAINT MONO (3434 1225);
FORCEPROP 2 LAST $XR0 302 
J 0
(3314 1225);
DISPLAY 0.638298 (3314 1225);
PAINT MONO (3314 1225);
FORCEPROP 1 LAST COMMENT_BODY TRUE
J 2
(3025 1150);
DISPLAY 1.170213 (3025 1150);
PAINT GREEN (3025 1150);
DISPLAY INVISIBLE (3025 1150);
FORCEPROP 1 LAST OFFPAGE TRUE
J 2
(2800 1100);
DISPLAY 0.872340 (2800 1100);
PAINT AQUA (2800 1100);
DISPLAY INVISIBLE (2800 1100);
FORCEPROP 2 LAST CDS_LIB standard
J 2
(3125 1225);
DISPLAY INVISIBLE (3125 1225);
FORCEPROP 2 LAST PATH I53
J 0
(3575 1275);
DISPLAY 1.021277 (3575 1275);
DISPLAY INVISIBLE (3575 1275);
FORCEADD OFFPAGE..5
R 2
(3125 1325);
FORCEPROP 2 LAST $XR2 301 
J 0
(3554 1325);
DISPLAY 0.638298 (3554 1325);
PAINT MONO (3554 1325);
FORCEPROP 2 LAST $XR1 303 
J 0
(3434 1325);
DISPLAY 0.638298 (3434 1325);
PAINT MONO (3434 1325);
FORCEPROP 2 LAST $XR0 302 
J 0
(3314 1325);
DISPLAY 0.638298 (3314 1325);
PAINT MONO (3314 1325);
FORCEPROP 1 LAST COMMENT_BODY TRUE
J 2
(3025 1250);
DISPLAY 1.170213 (3025 1250);
PAINT GREEN (3025 1250);
DISPLAY INVISIBLE (3025 1250);
FORCEPROP 1 LAST OFFPAGE TRUE
J 2
(2800 1200);
DISPLAY 0.872340 (2800 1200);
PAINT AQUA (2800 1200);
DISPLAY INVISIBLE (2800 1200);
FORCEPROP 2 LAST CDS_LIB standard
J 2
(3125 1325);
DISPLAY INVISIBLE (3125 1325);
FORCEPROP 2 LAST PATH I54
J 0
(3575 1375);
DISPLAY 1.021277 (3575 1375);
DISPLAY INVISIBLE (3575 1375);
FORCEADD OFFPAGE..4
(3125 1525);
FORCEPROP 2 LAST $XR2 303 
J 0
(3551 1525);
DISPLAY 0.638298 (3551 1525);
PAINT MONO (3551 1525);
FORCEPROP 2 LAST $XR1 302 
J 0
(3431 1525);
DISPLAY 0.638298 (3431 1525);
PAINT MONO (3431 1525);
FORCEPROP 2 LAST $XR0 301 
J 0
(3311 1525);
DISPLAY 0.638298 (3311 1525);
PAINT MONO (3311 1525);
FORCEPROP 1 LAST COMMENT_BODY TRUE
J 0
(3100 1425);
DISPLAY 0.872340 (3100 1425);
PAINT GREEN (3100 1425);
DISPLAY INVISIBLE (3100 1425);
FORCEPROP 1 LAST OFFPAGE TRUE
J 0
(3450 1400);
DISPLAY 0.872340 (3450 1400);
PAINT GREEN (3450 1400);
DISPLAY INVISIBLE (3450 1400);
FORCEPROP 2 LAST CDS_LIB standard
J 0
(3125 1525);
DISPLAY INVISIBLE (3125 1525);
FORCEPROP 2 LAST PATH I55
J 0
(3575 1575);
DISPLAY 1.021277 (3575 1575);
DISPLAY INVISIBLE (3575 1575);
FORCEADD OFFPAGE..5
R 2
(3125 1700);
FORCEPROP 2 LAST $XR2 301 
J 0
(3554 1700);
DISPLAY 0.638298 (3554 1700);
PAINT MONO (3554 1700);
FORCEPROP 2 LAST $XR1 303 
J 0
(3434 1700);
DISPLAY 0.638298 (3434 1700);
PAINT MONO (3434 1700);
FORCEPROP 2 LAST $XR0 302 
J 0
(3314 1700);
DISPLAY 0.638298 (3314 1700);
PAINT MONO (3314 1700);
FORCEPROP 1 LAST COMMENT_BODY TRUE
J 2
(3025 1625);
DISPLAY 1.170213 (3025 1625);
PAINT GREEN (3025 1625);
DISPLAY INVISIBLE (3025 1625);
FORCEPROP 1 LAST OFFPAGE TRUE
J 2
(2800 1575);
DISPLAY 0.872340 (2800 1575);
PAINT AQUA (2800 1575);
DISPLAY INVISIBLE (2800 1575);
FORCEPROP 2 LAST CDS_LIB standard
J 0
(3125 1700);
DISPLAY INVISIBLE (3125 1700);
FORCEPROP 2 LAST PATH I56
J 0
(3575 1750);
DISPLAY 1.021277 (3575 1750);
DISPLAY INVISIBLE (3575 1750);
FORCEADD UNIVERSAL_POWER..1
(-2750 -450);
FORCEPROP 3 LASTPIN (-2750 -500) SIG_NAME HSC_VDD\g
J 0
(-2740 -490);
DISPLAY 0.659574 (-2740 -490);
PAINT MONO (-2740 -490);
DISPLAY INVISIBLE (-2740 -490);
FORCEPROP 1 LAST HDL_POWER HSC_VDD
J 1
(-2750 -400);
DISPLAY 0.723404 (-2750 -400);
PAINT GREEN (-2750 -400);
FORCEPROP 2 LAST ROOM AUX_SW
J 0
(-2750 -350);
DISPLAY 0.617021 (-2750 -350);
DISPLAY INVISIBLE (-2750 -350);
FORCEPROP 2 LAST CDS_LIB logical_power
J 0
(-2750 -450);
DISPLAY INVISIBLE (-2750 -450);
FORCEPROP 2 LAST BOM_COST MIO_VRD_SB
J 0
(-2750 -350);
DISPLAY 0.617021 (-2750 -350);
PAINT PURPLE (-2750 -350);
DISPLAY INVISIBLE (-2750 -350);
FORCEPROP 1 LAST PATH I6
J 0
(-2700 -425);
DISPLAY 0.872340 (-2700 -425);
PAINT AQUA (-2700 -425);
DISPLAY INVISIBLE (-2700 -425);
FORCEADD OFFPAGE..4
R 2
(-2075 -1300);
FORCEPROP 2 LAST $XR2 303 
J 0
(-2327 -1336);
DISPLAY 0.638298 (-2327 -1336);
PAINT MONO (-2327 -1336);
FORCEPROP 2 LAST $XR1 302 
J 0
(-2447 -1300);
DISPLAY 0.638298 (-2447 -1300);
PAINT MONO (-2447 -1300);
FORCEPROP 2 LAST $XR0 301 
J 0
(-2327 -1300);
DISPLAY 0.638298 (-2327 -1300);
PAINT MONO (-2327 -1300);
FORCEPROP 1 LAST COMMENT_BODY TRUE
J 2
(-2050 -1400);
DISPLAY 0.872340 (-2050 -1400);
PAINT GREEN (-2050 -1400);
DISPLAY INVISIBLE (-2050 -1400);
FORCEPROP 1 LAST OFFPAGE TRUE
J 2
(-2400 -1425);
DISPLAY 0.872340 (-2400 -1425);
PAINT GREEN (-2400 -1425);
DISPLAY INVISIBLE (-2400 -1425);
FORCEPROP 2 LAST CDS_LIB standard
J 0
(-2075 -1300);
DISPLAY INVISIBLE (-2075 -1300);
FORCEPROP 2 LAST PATH I7
J 0
(-2325 -1250);
DISPLAY 1.021277 (-2325 -1250);
DISPLAY INVISIBLE (-2325 -1250);
FORCEADD UNIVERSAL_GND..1
(-1875 -1100);
FORCEPROP 3 LASTPIN (-1875 -1050) SIG_NAME AGND_HSC\g
J 0
(-1865 -1040);
DISPLAY 0.659574 (-1865 -1040);
PAINT MONO (-1865 -1040);
DISPLAY INVISIBLE (-1865 -1040);
FORCEPROP 1 LAST HDL_POWER AGND_HSC
J 1
(-1850 -1175);
DISPLAY 0.723404 (-1850 -1175);
PAINT GREEN (-1850 -1175);
FORCEPROP 2 LAST CDS_LIB logical_power
J 0
(-1875 -1100);
DISPLAY INVISIBLE (-1875 -1100);
FORCEPROP 1 LAST PATH I8
J 0
(-1800 -1100);
DISPLAY 0.872340 (-1800 -1100);
PAINT AQUA (-1800 -1100);
DISPLAY INVISIBLE (-1800 -1100);
FORCEADD OFFPAGE..4
R 2
(-1250 -1400);
FORCEPROP 2 LAST $XR2 303 
J 0
(-1772 -1400);
DISPLAY 0.638298 (-1772 -1400);
PAINT MONO (-1772 -1400);
FORCEPROP 2 LAST $XR1 302 
J 0
(-1652 -1400);
DISPLAY 0.638298 (-1652 -1400);
PAINT MONO (-1652 -1400);
FORCEPROP 2 LAST $XR0 301 
J 0
(-1532 -1400);
DISPLAY 0.638298 (-1532 -1400);
PAINT MONO (-1532 -1400);
FORCEPROP 1 LAST COMMENT_BODY TRUE
J 2
(-1225 -1500);
DISPLAY 0.872340 (-1225 -1500);
PAINT GREEN (-1225 -1500);
DISPLAY INVISIBLE (-1225 -1500);
FORCEPROP 1 LAST OFFPAGE TRUE
J 2
(-1575 -1525);
DISPLAY 0.872340 (-1575 -1525);
PAINT GREEN (-1575 -1525);
DISPLAY INVISIBLE (-1575 -1525);
FORCEPROP 2 LAST CDS_LIB standard
J 0
(-1250 -1400);
DISPLAY INVISIBLE (-1250 -1400);
FORCEPROP 2 LAST PATH I9
J 0
(-1525 -1350);
DISPLAY 1.021277 (-1525 -1350);
DISPLAY INVISIBLE (-1525 -1350);
FORCEADD DNS..2
(-1850 -1825);
PAINT RED (-1850 -1825);
FORCEPROP 1 LAST COMMENT_BODY TRUE
R 1
J 0
(-1775 -2050);
DISPLAY 0.872340 (-1775 -2050);
PAINT GREEN (-1775 -2050);
DISPLAY INVISIBLE (-1775 -2050);
FORCEPROP 2 LAST CDS_LIB mstr_misc
J 0
(-1850 -1825);
DISPLAY INVISIBLE (-1850 -1825);
FORCEADD DNS..2
(-1150 -1800);
PAINT RED (-1150 -1800);
FORCEPROP 1 LAST COMMENT_BODY TRUE
R 1
J 0
(-1075 -2025);
DISPLAY 0.872340 (-1075 -2025);
PAINT GREEN (-1075 -2025);
DISPLAY INVISIBLE (-1075 -2025);
FORCEPROP 2 LAST CDS_LIB mstr_misc
J 0
(-1150 -1800);
DISPLAY INVISIBLE (-1150 -1800);
FORCEADD DNS..2
(-1875 975);
PAINT RED (-1875 975);
FORCEPROP 1 LAST COMMENT_BODY TRUE
R 1
J 0
(-1800 750);
DISPLAY 0.872340 (-1800 750);
PAINT GREEN (-1800 750);
DISPLAY INVISIBLE (-1800 750);
FORCEPROP 2 LAST CDS_LIB mstr_misc
J 0
(-1875 975);
DISPLAY INVISIBLE (-1875 975);
FORCEADD DNS..2
(-1100 950);
PAINT RED (-1100 950);
FORCEPROP 1 LAST COMMENT_BODY TRUE
R 1
J 0
(-1025 725);
DISPLAY 0.872340 (-1025 725);
PAINT GREEN (-1025 725);
DISPLAY INVISIBLE (-1025 725);
FORCEPROP 2 LAST CDS_LIB mstr_misc
J 0
(-1100 950);
DISPLAY INVISIBLE (-1100 950);
FORCEADD QUANTA_TITLE_BLOCK_C..1
(5550 -3200);
FORCEPROP 0 LAST CDS_CON_LAST_MODIFIED Fri Aug 25 14:05:14 2023
J 0
(3665 -3185);
PAINT MONO (3665 -3185);
DISPLAY INVISIBLE (3665 -3185);
FORCEPROP 2 LAST CUSTOM_TXT_CDS <XR_PAGE_TITLE>
J 0
(-2340 2050);
DISPLAY 0.638298 (-2340 2050);
PAINT PINK (-2340 2050);
DISPLAY INVISIBLE (-2340 2050);
FORCEPROP 2 LAST CUSTOM_TXT_CDS <Q_REV>
J 0
(5366 -3097);
DISPLAY 1.212766 (5366 -3097);
FORCEPROP 2 LAST CUSTOM_TXT_CDS <CON_PAGE_NUM> OF <CON_TOTAL_PAGES>
J 0
(5104 -3182);
DISPLAY 0.978723 (5104 -3182);
FORCEPROP 2 LAST CUSTOM_TXT_CDS <Q_PROJ>
J 0
(3168 -3098);
DISPLAY 1.212766 (3168 -3098);
FORCEPROP 2 LAST CUSTOM_TXT_CDS <Q_NUMBER>
J 0
(4147 -3097);
DISPLAY 1.212766 (4147 -3097);
FORCEPROP 2 LAST CUSTOM_TXT_CDS <CON_LAST_MODIFIED>
J 0
(3665 -3185);
DISPLAY 0.978723 (3665 -3185);
FORCEPROP 1 LAST CUSTOM_TXT_CDS <NAME_2>
J 0
(2375 -3150);
FORCEPROP 1 LAST CUSTOM_TXT_CDS <NAME_1>
J 0
(2375 -3025);
FORCEPROP 1 LAST Q_TITLE HSC MP5990 (3/4)
J 0
(-3816 -3174);
DISPLAY 2.446809 (-3816 -3174);
PAINT GREEN (-3816 -3174);
FORCEPROP 1 LAST Q_DEPT 
J 1
(1787 -3151);
DISPLAY 1.957447 (1787 -3151);
PAINT GREEN (1787 -3151);
FORCEPROP 2 LAST CDS_XR_PAGE_TITLE CR-303 : @S9S_MB_2U_LIB.S9S_MB_2U(SCH_1):PAGE303
J 0
(-2340 2050);
DISPLAY 0.638298 (-2340 2050);
PAINT PINK (-2340 2050);
DISPLAY INVISIBLE (-2340 2050);
FORCEPROP 1 LAST CDS_LMAN_SYM_OUTLINE -9475,6775,100,-125
J 0
(5550 -3200);
DISPLAY 0.468085 (5550 -3200);
PAINT GREEN (5550 -3200);
DISPLAY INVISIBLE (5550 -3200);
FORCEPROP 2 LAST CDS_LIB pure_quanta
J 0
(5550 -3200);
PAINT MONO (5550 -3200);
DISPLAY INVISIBLE (5550 -3200);
FORCEPROP 2 LAST PAGE_BORDER TRUE
J 0
(-2340 2050);
DISPLAY 0.638298 (-2340 2050);
PAINT PINK (-2340 2050);
DISPLAY INVISIBLE (-2340 2050);
FORCEPROP 1 LAST COMMENT_BODY TRUE
J 0
(5562 -3213);
DISPLAY 0.978723 (5562 -3213);
PAINT GREEN (5562 -3213);
DISPLAY INVISIBLE (5562 -3213);
WIRE 16 -1 (-1875 -1050)(-1875 -1000);
WIRE 16 -1 (-1900 1750)(-1900 1775);
WIRE 16 -1 (-2775 1500)(-2775 1350);
WIRE 16 -1 (-1875 -2075)(-1875 -2000);
WIRE 16 -1 (-2750 -1275)(-2750 -1425);
WIRE 16 -1 (-2750 -500)(-2750 -600);
WIRE 16 -1 (-125 -250)(-125 -300);
WIRE 16 -1 (-1875 700)(-1875 775);
WIRE 16 -1 (-2775 2275)(-2775 2175);
WIRE 16 -1 (-125 2525)(-125 2475);
WIRE 16 -1 (1825 -1900)(1825 -1975);
WIRE 16 -1 (1950 -250)(1950 -275);
WIRE 16 -1 (1825 875)(1825 800);
WIRE 16 -1 (1950 2525)(1950 2500);
WIRE 16 -1 (-125 -300)(175 -300);
WIRE 16 -1 (175 -300)(175 -350);
WIRE 16 -1 (375 -350)(175 -350);
WIRE 16 -1 (175 -350)(175 -400);
WIRE 16 -1 (375 -400)(175 -400);
WIRE 16 -1 (175 -400)(175 -450);
WIRE 16 -1 (375 -450)(175 -450);
WIRE 16 -1 (175 -450)(175 -500);
WIRE 16 -1 (375 -500)(175 -500);
WIRE 16 -1 (375 -550)(175 -550);
WIRE 16 -1 (175 -500)(175 -550);
WIRE 16 -1 (175 -550)(175 -600);
WIRE 16 -1 (375 -600)(175 -600);
WIRE 16 -1 (175 -600)(175 -650);
WIRE 16 -1 (375 -650)(175 -650);
WIRE 16 -1 (175 -650)(175 -700);
WIRE 16 -1 (375 -700)(175 -700);
WIRE 16 -1 (175 -700)(175 -750);
WIRE 16 -1 (175 -750)(375 -750);
WIRE 16 -1 (-2750 -1075)(-2750 -900);
WIRE 16 -1 (-2750 -900)(375 -900);
FORCEPROP 2 LAST SIG_NAME HSC_VDD_R_4
J 0
(-160 -890);
DISPLAY 0.808511 (-160 -890);
WIRE 16 -1 (-2750 -800)(-2750 -900);
WIRE 16 -1 (-1875 -1000)(-1175 -1000);
WIRE 16 -1 (-1875 -1300)(-1875 -1725);
WIRE 16 -1 (-1875 -1300)(-2025 -1300);
WIRE 16 -1 (375 -1300)(-1875 -1300);
FORCEPROP 2 LAST SIG_NAME HSC_ON
J 0
(-160 -1290);
DISPLAY 0.808511 (-160 -1290);
WIRE 16 -1 (-1150 -1725)(-1150 -1400);
WIRE 16 -1 (375 -1400)(-1150 -1400);
FORCEPROP 2 LAST SIG_NAME HSC_OCREF
J 0
(-160 -1390);
DISPLAY 0.808511 (-160 -1390);
WIRE 16 -1 (-1200 -1400)(-1150 -1400);
WIRE 16 -1 (-650 -1500)(-650 -1725);
WIRE 16 -1 (375 -1500)(-650 -1500);
FORCEPROP 2 LAST SIG_NAME HSC_CS_4
J 0
(-160 -1490);
DISPLAY 0.808511 (-160 -1490);
WIRE 16 -1 (-1875 -1925)(-1875 -2000);
WIRE 16 -1 (-1150 -2000)(-1875 -2000);
WIRE 16 -1 (-1150 -1925)(-1150 -2000);
WIRE 16 -1 (-1150 -2000)(-650 -2000);
WIRE 16 -1 (-650 -1925)(-650 -2000);
WIRE 16 -1 (-125 -2000)(-650 -2000);
WIRE 16 -1 (-125 -1925)(-125 -2000);
WIRE 16 -1 (-125 -2000)(325 -2000);
WIRE 16 -1 (325 -1800)(325 -2000);
WIRE 16 -1 (375 -1800)(325 -1800);
WIRE 16 -1 (1325 -1550)(3050 -1550);
FORCEPROP 2 LAST SIG_NAME HSC_VTEMP
J 0
(1465 -1540);
DISPLAY 0.808511 (1465 -1540);
WIRE 16 -1 (1325 -1450)(3050 -1450);
FORCEPROP 2 LAST SIG_NAME HSC_FAULT
J 0
(1465 -1440);
DISPLAY 0.808511 (1465 -1440);
WIRE 16 -1 (2425 -1075)(3050 -1075);
FORCEPROP 2 LAST SIG_NAME HSC_D_OC_R
J 0
(2590 -1065);
DISPLAY 0.808511 (2590 -1065);
WIRE 16 -1 (2425 -1250)(3050 -1250);
FORCEPROP 2 LAST SIG_NAME HSC_FLT_TYPE
J 0
(2540 -1240);
DISPLAY 0.808511 (2540 -1240);
WIRE 16 -1 (-575 -1175)(-1150 -1175);
FORCEPROP 2 LAST SIG_NAME HSC_SCREF
J 0
(-1160 -1165);
DISPLAY 0.808511 (-1160 -1165);
WIRE 16 -1 (-125 -1725)(-125 -1600);
WIRE 16 -1 (375 -1600)(-125 -1600);
FORCEPROP 2 LAST SIG_NAME HSC_IMON
J 0
(-160 -1590);
DISPLAY 0.808511 (-160 -1590);
WIRE 16 -1 (-175 -1600)(-125 -1600);
WIRE 16 -1 (-50 -1175)(-375 -1175);
WIRE 16 -1 (-50 -1100)(-50 -1175);
WIRE 16 -1 (375 -1100)(-50 -1100);
FORCEPROP 2 LAST SIG_NAME HSC_SCREF_4
J 0
(-160 -1090);
DISPLAY 0.808511 (-160 -1090);
WIRE 16 -1 (-975 -1000)(375 -1000);
FORCEPROP 2 LAST SIG_NAME HSC_MODE_4
J 0
(-160 -990);
DISPLAY 0.808511 (-160 -990);
WIRE 16 -1 (1450 -800)(1325 -800);
WIRE 16 -1 (1450 -750)(1450 -800);
WIRE 16 -1 (1325 -750)(1450 -750);
WIRE 16 -1 (1325 -700)(1450 -700);
WIRE 16 -1 (1450 -700)(1450 -750);
WIRE 16 -1 (1325 -650)(1450 -650);
WIRE 16 -1 (1450 -650)(1450 -700);
WIRE 16 -1 (1325 -600)(1450 -600);
WIRE 16 -1 (1450 -600)(1450 -650);
WIRE 16 -1 (1325 -550)(1450 -550);
WIRE 16 -1 (1450 -550)(1450 -600);
WIRE 16 -1 (1450 -500)(1450 -550);
WIRE 16 -1 (1325 -500)(1450 -500);
WIRE 16 -1 (1325 -450)(1450 -450);
WIRE 16 -1 (1450 -450)(1450 -500);
WIRE 16 -1 (1325 -400)(1450 -400);
WIRE 16 -1 (1450 -400)(1450 -450);
WIRE 16 -1 (1325 -350)(1450 -350);
WIRE 16 -1 (1450 -350)(1450 -400);
WIRE 16 -1 (1450 -275)(1450 -350);
WIRE 16 -1 (1950 -275)(1450 -275);
WIRE 16 -1 (1325 -1350)(1800 -1350);
FORCEPROP 2 LAST SIG_NAME HSC_NC1_4
J 0
(1465 -1340);
DISPLAY 0.808511 (1465 -1340);
WIRE 16 -1 (1325 -1650)(1825 -1650);
FORCEPROP 2 LAST SIG_NAME HSC_SS
J 0
(1465 -1640);
DISPLAY 0.808511 (1465 -1640);
WIRE 16 -1 (1825 -1650)(1825 -1700);
WIRE 16 -1 (1825 -1650)(3050 -1650);
WIRE 16 -1 (1325 1125)(1825 1125);
FORCEPROP 2 LAST SIG_NAME HSC_SS
J 0
(1440 1135);
DISPLAY 0.808511 (1440 1135);
WIRE 16 -1 (1825 1125)(1825 1075);
WIRE 16 -1 (1825 1125)(3075 1125);
WIRE 16 -1 (1325 1225)(3075 1225);
FORCEPROP 2 LAST SIG_NAME HSC_VTEMP
J 0
(1440 1235);
DISPLAY 0.808511 (1440 1235);
WIRE 16 -1 (1325 1325)(3075 1325);
FORCEPROP 2 LAST SIG_NAME HSC_FAULT
J 0
(1440 1335);
DISPLAY 0.808511 (1440 1335);
WIRE 16 -1 (-1875 1475)(-1875 1050);
WIRE 16 -1 (-2000 1475)(-1875 1475);
WIRE 16 -1 (375 1475)(-1875 1475);
FORCEPROP 2 LAST SIG_NAME HSC_ON
J 0
(-185 1485);
DISPLAY 0.808511 (-185 1485);
WIRE 16 -1 (-1125 1050)(-1125 1375);
WIRE 16 -1 (-1125 1375)(375 1375);
FORCEPROP 2 LAST SIG_NAME HSC_OCREF
J 0
(-185 1385);
DISPLAY 0.808511 (-185 1385);
WIRE 16 -1 (-1175 1375)(-1125 1375);
WIRE 16 -1 (-650 1275)(-650 1050);
WIRE 16 -1 (375 1275)(-650 1275);
FORCEPROP 2 LAST SIG_NAME HSC_CS_3
J 0
(-185 1285);
DISPLAY 0.808511 (-185 1285);
WIRE 16 -1 (-175 1175)(-125 1175);
WIRE 16 -1 (375 1175)(-125 1175);
FORCEPROP 2 LAST SIG_NAME HSC_IMON
J 0
(-185 1185);
DISPLAY 0.808511 (-185 1185);
WIRE 16 -1 (-125 1050)(-125 1175);
WIRE 16 -1 (-975 1775)(375 1775);
FORCEPROP 2 LAST SIG_NAME HSC_MODE_3
J 0
(-185 1785);
DISPLAY 0.808511 (-185 1785);
WIRE 16 -1 (-2775 1700)(-2775 1875);
WIRE 16 -1 (-2775 1875)(375 1875);
FORCEPROP 2 LAST SIG_NAME HSC_VDD_R_3
J 0
(-185 1885);
DISPLAY 0.808511 (-185 1885);
WIRE 16 -1 (-2775 1975)(-2775 1875);
WIRE 16 -1 (-1900 1775)(-1175 1775);
WIRE 16 -1 (-50 1600)(-400 1600);
WIRE 16 -1 (-50 1675)(-50 1600);
WIRE 16 -1 (375 1675)(-50 1675);
FORCEPROP 2 LAST SIG_NAME HSC_SCREF_3
J 0
(-185 1685);
DISPLAY 0.808511 (-185 1685);
WIRE 16 -1 (-600 1600)(-1150 1600);
FORCEPROP 2 LAST SIG_NAME HSC_SCREF
J 0
(-1160 1610);
DISPLAY 0.808511 (-1160 1610);
WIRE 16 -1 (2425 1700)(3075 1700);
FORCEPROP 2 LAST SIG_NAME HSC_D_OC_R
J 0
(2640 1710);
DISPLAY 0.808511 (2640 1710);
WIRE 16 -1 (2425 1525)(3075 1525);
FORCEPROP 2 LAST SIG_NAME HSC_FLT_TYPE
J 0
(2565 1535);
DISPLAY 0.808511 (2565 1535);
WIRE 16 -1 (1950 2500)(1450 2500);
WIRE 16 -1 (1325 2425)(1450 2425);
WIRE 16 -1 (1450 2500)(1450 2425);
WIRE 16 -1 (1325 2375)(1450 2375);
WIRE 16 -1 (1450 2425)(1450 2375);
WIRE 16 -1 (1325 2325)(1450 2325);
WIRE 16 -1 (1450 2375)(1450 2325);
WIRE 16 -1 (1325 2275)(1450 2275);
WIRE 16 -1 (1450 2325)(1450 2275);
WIRE 16 -1 (1325 2225)(1450 2225);
WIRE 16 -1 (1450 2275)(1450 2225);
WIRE 16 -1 (1325 2175)(1450 2175);
WIRE 16 -1 (1450 2225)(1450 2175);
WIRE 16 -1 (1325 2125)(1450 2125);
WIRE 16 -1 (1450 2175)(1450 2125);
WIRE 16 -1 (1325 2075)(1450 2075);
WIRE 16 -1 (1450 2125)(1450 2075);
WIRE 16 -1 (1325 2025)(1450 2025);
WIRE 16 -1 (1450 2075)(1450 2025);
WIRE 16 -1 (1450 2025)(1450 1975);
WIRE 16 -1 (1450 1975)(1325 1975);
WIRE 16 -1 (1325 1525)(2225 1525);
FORCEPROP 2 LAST SIG_NAME HSC_FLT_TYPE_3
J 0
(1440 1535);
DISPLAY 0.808511 (1440 1535);
WIRE 16 -1 (1450 1700)(2225 1700);
WIRE 16 -1 (1450 1625)(1450 1700);
FORCEPROP 2 LAST SIG_NAME HSC_D_OC_3
J 0
(1440 1710);
DISPLAY 0.808511 (1440 1710);
WIRE 16 -1 (1450 1625)(1325 1625);
WIRE 16 -1 (1325 1425)(1775 1425);
FORCEPROP 2 LAST SIG_NAME HSC_NC1_3
J 0
(1440 1435);
DISPLAY 0.808511 (1440 1435);
WIRE 16 -1 (1325 -1250)(2225 -1250);
FORCEPROP 2 LAST SIG_NAME HSC_FLT_TYPE_4
J 0
(1465 -1240);
DISPLAY 0.808511 (1465 -1240);
WIRE 16 -1 (1400 -1075)(2225 -1075);
WIRE 16 -1 (1400 -1150)(1325 -1150);
WIRE 16 -1 (1400 -1150)(1400 -1075);
FORCEPROP 2 LAST SIG_NAME HSC_D_OC_4
J 0
(1465 -1065);
DISPLAY 0.808511 (1465 -1065);
WIRE 16 -1 (-125 2475)(175 2475);
WIRE 16 -1 (175 2475)(175 2425);
WIRE 16 -1 (375 2425)(175 2425);
WIRE 16 -1 (175 2425)(175 2375);
WIRE 16 -1 (375 2375)(175 2375);
WIRE 16 -1 (175 2375)(175 2325);
WIRE 16 -1 (375 2325)(175 2325);
WIRE 16 -1 (175 2325)(175 2275);
WIRE 16 -1 (375 2275)(175 2275);
WIRE 16 -1 (175 2275)(175 2225);
WIRE 16 -1 (375 2225)(175 2225);
WIRE 16 -1 (175 2225)(175 2175);
WIRE 16 -1 (375 2175)(175 2175);
WIRE 16 -1 (175 2175)(175 2125);
WIRE 16 -1 (375 2125)(175 2125);
WIRE 16 -1 (175 2025)(375 2025);
WIRE 16 -1 (175 2075)(175 2025);
WIRE 16 -1 (175 2125)(175 2075);
WIRE 16 -1 (375 2075)(175 2075);
WIRE 16 -1 (375 975)(325 975);
WIRE 16 -1 (325 975)(325 775);
WIRE 16 -1 (-125 850)(-125 775);
WIRE 16 -1 (-125 775)(325 775);
WIRE 16 -1 (-650 850)(-650 775);
WIRE 16 -1 (-125 775)(-650 775);
WIRE 16 -1 (-1125 850)(-1125 775);
WIRE 16 -1 (-1125 775)(-650 775);
WIRE 16 -1 (-1125 775)(-1875 775);
WIRE 16 -1 (-1875 850)(-1875 775);
DOT 1 (-1875 -1300);
DOT 1 (-1150 -2000);
DOT 1 (-125 -2000);
DOT 1 (-1150 -1400);
DOT 1 (175 -650);
DOT 1 (175 -700);
DOT 1 (175 -600);
DOT 1 (175 -500);
DOT 1 (175 -400);
DOT 1 (175 -450);
DOT 1 (175 -350);
DOT 1 (-2775 1875);
DOT 1 (-1875 775);
DOT 1 (-1875 1475);
DOT 1 (-1125 775);
DOT 1 (-650 775);
DOT 1 (-1125 1375);
DOT 1 (-125 775);
DOT 1 (-125 1175);
DOT 1 (175 2075);
DOT 1 (175 2125);
DOT 1 (175 2175);
DOT 1 (175 2225);
DOT 1 (175 2275);
DOT 1 (175 2325);
DOT 1 (175 2375);
DOT 1 (175 2425);
DOT 1 (1825 -1650);
DOT 1 (1450 -750);
DOT 1 (1450 -700);
DOT 1 (1450 -650);
DOT 1 (1450 -600);
DOT 1 (1450 -550);
DOT 1 (1450 -500);
DOT 1 (1450 -450);
DOT 1 (1450 -400);
DOT 1 (1450 -350);
DOT 1 (1825 1125);
DOT 1 (1450 2025);
DOT 1 (1450 2075);
DOT 1 (1450 2125);
DOT 1 (1450 2175);
DOT 1 (1450 2225);
DOT 1 (1450 2275);
DOT 1 (1450 2325);
DOT 1 (1450 2375);
DOT 1 (1450 2425);
DOT 1 (-1875 -2000);
DOT 1 (-2750 -900);
DOT 1 (-650 -2000);
DOT 1 (-125 -1600);
DOT 1 (175 -550);
FORCENOTE
OV =14.333V
(-3650 3000) 0;
DISPLAY LEFT (-3650 3000);
DISPLAY 1.021277 (-3650 3000);
FORCENOTE
LATCH OFF MODE
(-3650 2825) 0;
DISPLAY LEFT (-3650 2825);
DISPLAY 1.021277 (-3650 2825);
FORCENOTE
FOR MP5981:
(375 -2285) 0;
DISPLAY LEFT (375 -2285);
DISPLAY 1.021277 (375 -2285);
FORCENOTE
DNI PR3994, PR3995, PR3989
(375 -2350) 0;
DISPLAY LEFT (375 -2350);
DISPLAY 1.021277 (375 -2350);
FORCENOTE
CHANGE PU297 TO AL005981A00
(375 -2415) 0;
DISPLAY LEFT (375 -2415);
DISPLAY 1.021277 (375 -2415);
FORCENOTE
20211116 MODIFY FOR GT
(-500 3200) 0;
DISPLAY LEFT (-500 3200);
DISPLAY 2.510638 (-500 3200);
PAINT PINK (-500 3200);
FORCENOTE
FOR MP5981:
(400 540) 0;
DISPLAY LEFT (400 540);
DISPLAY 1.021277 (400 540);
FORCENOTE
SOFT START TIME=6MS.
(2325 -1860) 0;
DISPLAY LEFT (2325 -1860);
DISPLAY 1.021277 (2325 -1860);
FORCENOTE
VOUT SLEW RATE: 2V/MS
(2325 -1925) 0;
DISPLAY LEFT (2325 -1925);
DISPLAY 1.021277 (2325 -1925);
FORCENOTE
VOUT SLEW RATE: 2V/MS
(2325 850) 0;
DISPLAY LEFT (2325 850);
DISPLAY 1.021277 (2325 850);
FORCENOTE
SOFT START TIME=6MS.
(2325 916) 0;
DISPLAY LEFT (2325 916);
DISPLAY 1.021277 (2325 916);
FORCENOTE
OCP=240A
(-3675 3159) 0;
DISPLAY LEFT (-3675 3159);
DISPLAY 1.595745 (-3675 3159);
FORCENOTE
HOT SWAT CIRCUIT
(-3671 3263) 0;
DISPLAY LEFT (-3671 3263);
DISPLAY 2.000000 (-3671 3263);
FORCENOTE
FPH=220A
(-2950 3084) 0;
DISPLAY LEFT (-2950 3084);
DISPLAY 1.595745 (-2950 3084);
FORCENOTE
OCW=220A
(-3675 3084) 0;
DISPLAY LEFT (-3675 3084);
DISPLAY 1.595745 (-3675 3084);
FORCENOTE
UV =10.091V
(-3650 2950) 0;
DISPLAY LEFT (-3650 2950);
DISPLAY 1.021277 (-3650 2950);
FORCENOTE
ADDRESS 0X20
(-3650 2891) 0;
DISPLAY LEFT (-3650 2891);
DISPLAY 1.021277 (-3650 2891);
FORCENOTE
DNI PR3992, PR3993, PR3988
(400 475) 0;
DISPLAY LEFT (400 475);
DISPLAY 1.021277 (400 475);
FORCENOTE
CHANGE PU296 TO AL005981A00
(400 410) 0;
DISPLAY LEFT (400 410);
DISPLAY 1.021277 (400 410);
QUIT
